FILE_TYPE = MACRO_DRAWING;
SET COLOR_WIRE YELLOW;
SET COLOR_PROP ORANGE;
SET COLOR_DOT WHITE;
SET COLOR_ARC YELLOW;
SET COLOR_BODY GREEN;
SET COLOR_NOTE PURPLE;
SET PROP_DISPLAY VALUE;
SET PAGE_NUMBER P30;
FORCEADD SOCKET4677_AZIF0045P001C01CS..19
(1100 3025);
FORCEPROP 1 LAST PART_NUMBER DGA^7000023
J 0
(50 4075);
DISPLAY 0.723404 (50 4075);
PAINT GREEN (50 4075);
DISPLAY INVISIBLE (50 4075);
FORCEPROP 2 LAST VALUE SOCKET4677_AZIF0045-P001C01CS
J 0
(50 4200);
DISPLAY 1.021277 (50 4200);
FORCEPROP 1 LAST MATERIAL IO
J 0
(50 4000);
DISPLAY 0.723404 (50 4000);
PAINT GREEN (50 4000);
FORCEPROP 2 LAST PART_TYPE SMLF
J 0
(50 4250);
DISPLAY 1.021277 (50 4250);
FORCEPROP 1 LAST $LOCATION U2
J 0
(50 4150);
DISPLAY 0.723404 (50 4150);
PAINT GREEN (50 4150);
FORCEPROP 0 LASTPIN (-100 2225) $PN CU9
J 2
(-110 2235);
DISPLAY 0.680851 (-110 2235);
PAINT MONO (-110 2235);
FORCEPROP 0 LASTPIN (-100 2275) $PN CY10
J 2
(-110 2285);
DISPLAY 0.680851 (-110 2285);
PAINT MONO (-110 2285);
FORCEPROP 0 LASTPIN (-100 2325) $PN DA9
J 2
(-110 2335);
DISPLAY 0.680851 (-110 2335);
PAINT MONO (-110 2335);
FORCEPROP 0 LASTPIN (-100 2375) $PN DD10
J 2
(-110 2385);
DISPLAY 0.680851 (-110 2385);
PAINT MONO (-110 2385);
FORCEPROP 0 LASTPIN (-100 2425) $PN DE9
J 2
(-110 2435);
DISPLAY 0.680851 (-110 2435);
PAINT MONO (-110 2435);
FORCEPROP 0 LASTPIN (-100 2475) $PN DH10
J 2
(-110 2485);
DISPLAY 0.680851 (-110 2485);
PAINT MONO (-110 2485);
FORCEPROP 0 LASTPIN (-100 2525) $PN DJ9
J 2
(-110 2535);
DISPLAY 0.680851 (-110 2535);
PAINT MONO (-110 2535);
FORCEPROP 0 LASTPIN (-100 2575) $PN DM10
J 2
(-110 2585);
DISPLAY 0.680851 (-110 2585);
PAINT MONO (-110 2585);
FORCEPROP 0 LASTPIN (-100 2625) $PN DN9
J 2
(-110 2635);
DISPLAY 0.680851 (-110 2635);
PAINT MONO (-110 2635);
FORCEPROP 0 LASTPIN (-100 2675) $PN DT10
J 2
(-110 2685);
DISPLAY 0.680851 (-110 2685);
PAINT MONO (-110 2685);
FORCEPROP 0 LASTPIN (-100 2725) $PN DU9
J 2
(-110 2735);
DISPLAY 0.680851 (-110 2735);
PAINT MONO (-110 2735);
FORCEPROP 0 LASTPIN (-100 2775) $PN DY10
J 2
(-110 2785);
DISPLAY 0.680851 (-110 2785);
PAINT MONO (-110 2785);
FORCEPROP 0 LASTPIN (-100 2825) $PN EA9
J 2
(-110 2835);
DISPLAY 0.680851 (-110 2835);
PAINT MONO (-110 2835);
FORCEPROP 0 LASTPIN (-100 2875) $PN ED10
J 2
(-110 2885);
DISPLAY 0.680851 (-110 2885);
PAINT MONO (-110 2885);
FORCEPROP 0 LASTPIN (-100 2925) $PN EE9
J 2
(-110 2935);
DISPLAY 0.680851 (-110 2935);
PAINT MONO (-110 2935);
FORCEPROP 0 LASTPIN (-100 2975) $PN EH10
J 2
(-110 2985);
DISPLAY 0.680851 (-110 2985);
PAINT MONO (-110 2985);
FORCEPROP 0 LASTPIN (-100 3075) $PN CV10
J 2
(-110 3085);
DISPLAY 0.680851 (-110 3085);
PAINT MONO (-110 3085);
FORCEPROP 0 LASTPIN (-100 3125) $PN CW11
J 2
(-110 3135);
DISPLAY 0.680851 (-110 3135);
PAINT MONO (-110 3135);
FORCEPROP 0 LASTPIN (-100 3175) $PN DB10
J 2
(-110 3185);
DISPLAY 0.680851 (-110 3185);
PAINT MONO (-110 3185);
FORCEPROP 0 LASTPIN (-100 3225) $PN DC11
J 2
(-110 3235);
DISPLAY 0.680851 (-110 3235);
PAINT MONO (-110 3235);
FORCEPROP 0 LASTPIN (-100 3275) $PN DF10
J 2
(-110 3285);
DISPLAY 0.680851 (-110 3285);
PAINT MONO (-110 3285);
FORCEPROP 0 LASTPIN (-100 3325) $PN DG11
J 2
(-110 3335);
DISPLAY 0.680851 (-110 3335);
PAINT MONO (-110 3335);
FORCEPROP 0 LASTPIN (-100 3375) $PN DK10
J 2
(-110 3385);
DISPLAY 0.680851 (-110 3385);
PAINT MONO (-110 3385);
FORCEPROP 0 LASTPIN (-100 3425) $PN DL11
J 2
(-110 3435);
DISPLAY 0.680851 (-110 3435);
PAINT MONO (-110 3435);
FORCEPROP 0 LASTPIN (-100 3475) $PN DP10
J 2
(-110 3485);
DISPLAY 0.680851 (-110 3485);
PAINT MONO (-110 3485);
FORCEPROP 0 LASTPIN (-100 3525) $PN DR11
J 2
(-110 3535);
DISPLAY 0.680851 (-110 3535);
PAINT MONO (-110 3535);
FORCEPROP 0 LASTPIN (-100 3575) $PN DV10
J 2
(-110 3585);
DISPLAY 0.680851 (-110 3585);
PAINT MONO (-110 3585);
FORCEPROP 0 LASTPIN (-100 3625) $PN DW11
J 2
(-110 3635);
DISPLAY 0.680851 (-110 3635);
PAINT MONO (-110 3635);
FORCEPROP 0 LASTPIN (-100 3675) $PN EB10
J 2
(-110 3685);
DISPLAY 0.680851 (-110 3685);
PAINT MONO (-110 3685);
FORCEPROP 0 LASTPIN (-100 3725) $PN EC11
J 2
(-110 3735);
DISPLAY 0.680851 (-110 3735);
PAINT MONO (-110 3735);
FORCEPROP 0 LASTPIN (-100 3775) $PN EF10
J 2
(-110 3785);
DISPLAY 0.680851 (-110 3785);
PAINT MONO (-110 3785);
FORCEPROP 0 LASTPIN (-100 3825) $PN EG11
J 2
(-110 3835);
DISPLAY 0.680851 (-110 3835);
PAINT MONO (-110 3835);
FORCEPROP 0 LASTPIN (2300 2225) $PN CU13
J 0
(2310 2235);
DISPLAY 0.680851 (2310 2235);
PAINT MONO (2310 2235);
FORCEPROP 0 LASTPIN (2300 2275) $PN CV14
J 0
(2310 2285);
DISPLAY 0.680851 (2310 2285);
PAINT MONO (2310 2285);
FORCEPROP 0 LASTPIN (2300 2325) $PN DA13
J 0
(2310 2335);
DISPLAY 0.680851 (2310 2335);
PAINT MONO (2310 2335);
FORCEPROP 0 LASTPIN (2300 2375) $PN DB14
J 0
(2310 2385);
DISPLAY 0.680851 (2310 2385);
PAINT MONO (2310 2385);
FORCEPROP 0 LASTPIN (2300 2425) $PN DE13
J 0
(2310 2435);
DISPLAY 0.680851 (2310 2435);
PAINT MONO (2310 2435);
FORCEPROP 0 LASTPIN (2300 2475) $PN DF14
J 0
(2310 2485);
DISPLAY 0.680851 (2310 2485);
PAINT MONO (2310 2485);
FORCEPROP 0 LASTPIN (2300 2525) $PN DJ13
J 0
(2310 2535);
DISPLAY 0.680851 (2310 2535);
PAINT MONO (2310 2535);
FORCEPROP 0 LASTPIN (2300 2575) $PN DK14
J 0
(2310 2585);
DISPLAY 0.680851 (2310 2585);
PAINT MONO (2310 2585);
FORCEPROP 0 LASTPIN (2300 2625) $PN DN13
J 0
(2310 2635);
DISPLAY 0.680851 (2310 2635);
PAINT MONO (2310 2635);
FORCEPROP 0 LASTPIN (2300 2675) $PN DP14
J 0
(2310 2685);
DISPLAY 0.680851 (2310 2685);
PAINT MONO (2310 2685);
FORCEPROP 0 LASTPIN (2300 2725) $PN DU13
J 0
(2310 2735);
DISPLAY 0.680851 (2310 2735);
PAINT MONO (2310 2735);
FORCEPROP 0 LASTPIN (2300 2775) $PN DV14
J 0
(2310 2785);
DISPLAY 0.680851 (2310 2785);
PAINT MONO (2310 2785);
FORCEPROP 0 LASTPIN (2300 2825) $PN EA13
J 0
(2310 2835);
DISPLAY 0.680851 (2310 2835);
PAINT MONO (2310 2835);
FORCEPROP 0 LASTPIN (2300 2875) $PN EB14
J 0
(2310 2885);
DISPLAY 0.680851 (2310 2885);
PAINT MONO (2310 2885);
FORCEPROP 0 LASTPIN (2300 2925) $PN EE13
J 0
(2310 2935);
DISPLAY 0.680851 (2310 2935);
PAINT MONO (2310 2935);
FORCEPROP 0 LASTPIN (2300 2975) $PN EF14
J 0
(2310 2985);
DISPLAY 0.680851 (2310 2985);
PAINT MONO (2310 2985);
FORCEPROP 0 LASTPIN (2300 3075) $PN CT14
J 0
(2310 3085);
DISPLAY 0.680851 (2310 3085);
PAINT MONO (2310 3085);
FORCEPROP 0 LASTPIN (2300 3125) $PN CW15
J 0
(2310 3135);
DISPLAY 0.680851 (2310 3135);
PAINT MONO (2310 3135);
FORCEPROP 0 LASTPIN (2300 3175) $PN CY14
J 0
(2310 3185);
DISPLAY 0.680851 (2310 3185);
PAINT MONO (2310 3185);
FORCEPROP 0 LASTPIN (2300 3225) $PN DC15
J 0
(2310 3235);
DISPLAY 0.680851 (2310 3235);
PAINT MONO (2310 3235);
FORCEPROP 0 LASTPIN (2300 3275) $PN DD14
J 0
(2310 3285);
DISPLAY 0.680851 (2310 3285);
PAINT MONO (2310 3285);
FORCEPROP 0 LASTPIN (2300 3325) $PN DG15
J 0
(2310 3335);
DISPLAY 0.680851 (2310 3335);
PAINT MONO (2310 3335);
FORCEPROP 0 LASTPIN (2300 3375) $PN DH14
J 0
(2310 3385);
DISPLAY 0.680851 (2310 3385);
PAINT MONO (2310 3385);
FORCEPROP 0 LASTPIN (2300 3425) $PN DL15
J 0
(2310 3435);
DISPLAY 0.680851 (2310 3435);
PAINT MONO (2310 3435);
FORCEPROP 0 LASTPIN (2300 3475) $PN DM14
J 0
(2310 3485);
DISPLAY 0.680851 (2310 3485);
PAINT MONO (2310 3485);
FORCEPROP 0 LASTPIN (2300 3525) $PN DR15
J 0
(2310 3535);
DISPLAY 0.680851 (2310 3535);
PAINT MONO (2310 3535);
FORCEPROP 0 LASTPIN (2300 3575) $PN DT14
J 0
(2310 3585);
DISPLAY 0.680851 (2310 3585);
PAINT MONO (2310 3585);
FORCEPROP 0 LASTPIN (2300 3625) $PN DW15
J 0
(2310 3635);
DISPLAY 0.680851 (2310 3635);
PAINT MONO (2310 3635);
FORCEPROP 0 LASTPIN (2300 3675) $PN DY14
J 0
(2310 3685);
DISPLAY 0.680851 (2310 3685);
PAINT MONO (2310 3685);
FORCEPROP 0 LASTPIN (2300 3725) $PN EC15
J 0
(2310 3735);
DISPLAY 0.680851 (2310 3735);
PAINT MONO (2310 3735);
FORCEPROP 0 LASTPIN (2300 3775) $PN ED14
J 0
(2310 3785);
DISPLAY 0.680851 (2310 3785);
PAINT MONO (2310 3785);
FORCEPROP 0 LASTPIN (2300 3825) $PN EG15
J 0
(2310 3835);
DISPLAY 0.680851 (2310 3835);
PAINT MONO (2310 3835);
FORCEPROP 1 LAST CDS_LMAN_SYM_OUTLINE -1050,950,1050,-950
J 0
(1100 3025);
DISPLAY 0.468085 (1100 3025);
PAINT GREEN (1100 3025);
DISPLAY INVISIBLE (1100 3025);
FORCEPROP 1 LAST NEEDS_NO_SIZE TRUE
J 0
(1100 3025);
DISPLAY 0.723404 (1100 3025);
PAINT GREEN (1100 3025);
DISPLAY INVISIBLE (1100 3025);
FORCEPROP 2 LAST CDS_LIB pure_quanta
J 0
(1100 3025);
DISPLAY INVISIBLE (1100 3025);
FORCEPROP 2 LAST CDS_LOCATION U2
J 0
(50 4300);
DISPLAY 1.021277 (50 4300);
DISPLAY INVISIBLE (50 4300);
FORCEPROP 0 LAST $SEC 19
J 0
(50 4300);
DISPLAY 0.680851 (50 4300);
PAINT MONO (50 4300);
DISPLAY INVISIBLE (50 4300);
FORCEPROP 2 LAST CDS_SEC 19
J 0
(50 4300);
DISPLAY 1.021277 (50 4300);
DISPLAY INVISIBLE (50 4300);
FORCEPROP 1 LAST PATH I139
J 0
(1100 3025);
DISPLAY 0.723404 (1100 3025);
PAINT GREEN (1100 3025);
DISPLAY INVISIBLE (1100 3025);
FORCEADD SOCKET4677_AZIF0045P001C01CS..20
(1100 250);
FORCEPROP 1 LAST PART_NUMBER DGA^7000023
J 0
(50 1300);
DISPLAY 0.723404 (50 1300);
PAINT GREEN (50 1300);
DISPLAY INVISIBLE (50 1300);
FORCEPROP 2 LAST VALUE SOCKET4677_AZIF0045-P001C01CS
J 0
(50 1425);
DISPLAY 1.021277 (50 1425);
FORCEPROP 1 LAST MATERIAL IO
J 0
(50 1225);
DISPLAY 0.723404 (50 1225);
PAINT GREEN (50 1225);
FORCEPROP 2 LAST PART_TYPE SMLF
J 0
(50 1475);
DISPLAY 1.021277 (50 1475);
FORCEPROP 1 LAST $LOCATION U2
J 0
(50 1375);
DISPLAY 0.723404 (50 1375);
PAINT GREEN (50 1375);
FORCEPROP 0 LASTPIN (-100 -550) $PN EH89
J 2
(-110 -540);
DISPLAY 0.680851 (-110 -540);
PAINT MONO (-110 -540);
FORCEPROP 0 LASTPIN (-100 -500) $PN ED91
J 2
(-110 -490);
DISPLAY 0.680851 (-110 -490);
PAINT MONO (-110 -490);
FORCEPROP 0 LASTPIN (-100 -450) $PN EC90
J 2
(-110 -440);
DISPLAY 0.680851 (-110 -440);
PAINT MONO (-110 -440);
FORCEPROP 0 LASTPIN (-100 -400) $PN DY91
J 2
(-110 -390);
DISPLAY 0.680851 (-110 -390);
PAINT MONO (-110 -390);
FORCEPROP 0 LASTPIN (-100 -350) $PN DV89
J 2
(-110 -340);
DISPLAY 0.680851 (-110 -340);
PAINT MONO (-110 -340);
FORCEPROP 0 LASTPIN (-100 -300) $PN DU90
J 2
(-110 -290);
DISPLAY 0.680851 (-110 -290);
PAINT MONO (-110 -290);
FORCEPROP 0 LASTPIN (-100 -250) $PN DP89
J 2
(-110 -240);
DISPLAY 0.680851 (-110 -240);
PAINT MONO (-110 -240);
FORCEPROP 0 LASTPIN (-100 -200) $PN DN90
J 2
(-110 -190);
DISPLAY 0.680851 (-110 -190);
PAINT MONO (-110 -190);
FORCEPROP 0 LASTPIN (-100 -150) $PN DL90
J 2
(-110 -140);
DISPLAY 0.680851 (-110 -140);
PAINT MONO (-110 -140);
FORCEPROP 0 LASTPIN (-100 -100) $PN DH91
J 2
(-110 -90);
DISPLAY 0.680851 (-110 -90);
PAINT MONO (-110 -90);
FORCEPROP 0 LASTPIN (-100 -50) $PN DG90
J 2
(-110 -40);
DISPLAY 0.680851 (-110 -40);
PAINT MONO (-110 -40);
FORCEPROP 0 LASTPIN (-100 0) $PN DD91
J 2
(-110 10);
DISPLAY 0.680851 (-110 10);
PAINT MONO (-110 10);
FORCEPROP 0 LASTPIN (-100 50) $PN DB89
J 2
(-110 60);
DISPLAY 0.680851 (-110 60);
PAINT MONO (-110 60);
FORCEPROP 0 LASTPIN (-100 100) $PN DA90
J 2
(-110 110);
DISPLAY 0.680851 (-110 110);
PAINT MONO (-110 110);
FORCEPROP 0 LASTPIN (-100 150) $PN CV89
J 2
(-110 160);
DISPLAY 0.680851 (-110 160);
PAINT MONO (-110 160);
FORCEPROP 0 LASTPIN (-100 200) $PN CU90
J 2
(-110 210);
DISPLAY 0.680851 (-110 210);
PAINT MONO (-110 210);
FORCEPROP 0 LASTPIN (-100 300) $PN EJ90
J 2
(-110 310);
DISPLAY 0.680851 (-110 310);
PAINT MONO (-110 310);
FORCEPROP 0 LASTPIN (-100 350) $PN EE90
J 2
(-110 360);
DISPLAY 0.680851 (-110 360);
PAINT MONO (-110 360);
FORCEPROP 0 LASTPIN (-100 400) $PN EB89
J 2
(-110 410);
DISPLAY 0.680851 (-110 410);
PAINT MONO (-110 410);
FORCEPROP 0 LASTPIN (-100 450) $PN EA90
J 2
(-110 460);
DISPLAY 0.680851 (-110 460);
PAINT MONO (-110 460);
FORCEPROP 0 LASTPIN (-100 500) $PN DW90
J 2
(-110 510);
DISPLAY 0.680851 (-110 510);
PAINT MONO (-110 510);
FORCEPROP 0 LASTPIN (-100 550) $PN DT91
J 2
(-110 560);
DISPLAY 0.680851 (-110 560);
PAINT MONO (-110 560);
FORCEPROP 0 LASTPIN (-100 600) $PN DR90
J 2
(-110 610);
DISPLAY 0.680851 (-110 610);
PAINT MONO (-110 610);
FORCEPROP 0 LASTPIN (-100 650) $PN DM91
J 2
(-110 660);
DISPLAY 0.680851 (-110 660);
PAINT MONO (-110 660);
FORCEPROP 0 LASTPIN (-100 700) $PN DK89
J 2
(-110 710);
DISPLAY 0.680851 (-110 710);
PAINT MONO (-110 710);
FORCEPROP 0 LASTPIN (-100 750) $PN DJ90
J 2
(-110 760);
DISPLAY 0.680851 (-110 760);
PAINT MONO (-110 760);
FORCEPROP 0 LASTPIN (-100 800) $PN DF89
J 2
(-110 810);
DISPLAY 0.680851 (-110 810);
PAINT MONO (-110 810);
FORCEPROP 0 LASTPIN (-100 850) $PN DE90
J 2
(-110 860);
DISPLAY 0.680851 (-110 860);
PAINT MONO (-110 860);
FORCEPROP 0 LASTPIN (-100 900) $PN DC90
J 2
(-110 910);
DISPLAY 0.680851 (-110 910);
PAINT MONO (-110 910);
FORCEPROP 0 LASTPIN (-100 950) $PN CY91
J 2
(-110 960);
DISPLAY 0.680851 (-110 960);
PAINT MONO (-110 960);
FORCEPROP 0 LASTPIN (-100 1000) $PN CW90
J 2
(-110 1010);
DISPLAY 0.680851 (-110 1010);
PAINT MONO (-110 1010);
FORCEPROP 0 LASTPIN (-100 1050) $PN CT91
J 2
(-110 1060);
DISPLAY 0.680851 (-110 1060);
PAINT MONO (-110 1060);
FORCEPROP 0 LASTPIN (2300 -550) $PN EE86
J 0
(2310 -540);
DISPLAY 0.680851 (2310 -540);
PAINT MONO (2310 -540);
FORCEPROP 0 LASTPIN (2300 -500) $PN EB85
J 0
(2310 -490);
DISPLAY 0.680851 (2310 -490);
PAINT MONO (2310 -490);
FORCEPROP 0 LASTPIN (2300 -450) $PN DY87
J 0
(2310 -440);
DISPLAY 0.680851 (2310 -440);
PAINT MONO (2310 -440);
FORCEPROP 0 LASTPIN (2300 -400) $PN DV85
J 0
(2310 -390);
DISPLAY 0.680851 (2310 -390);
PAINT MONO (2310 -390);
FORCEPROP 0 LASTPIN (2300 -350) $PN DT87
J 0
(2310 -340);
DISPLAY 0.680851 (2310 -340);
PAINT MONO (2310 -340);
FORCEPROP 0 LASTPIN (2300 -300) $PN DP85
J 0
(2310 -290);
DISPLAY 0.680851 (2310 -290);
PAINT MONO (2310 -290);
FORCEPROP 0 LASTPIN (2300 -250) $PN DM87
J 0
(2310 -240);
DISPLAY 0.680851 (2310 -240);
PAINT MONO (2310 -240);
FORCEPROP 0 LASTPIN (2300 -200) $PN DK85
J 0
(2310 -190);
DISPLAY 0.680851 (2310 -190);
PAINT MONO (2310 -190);
FORCEPROP 0 LASTPIN (2300 -150) $PN DH87
J 0
(2310 -140);
DISPLAY 0.680851 (2310 -140);
PAINT MONO (2310 -140);
FORCEPROP 0 LASTPIN (2300 -100) $PN DF85
J 0
(2310 -90);
DISPLAY 0.680851 (2310 -90);
PAINT MONO (2310 -90);
FORCEPROP 0 LASTPIN (2300 -50) $PN DD87
J 0
(2310 -40);
DISPLAY 0.680851 (2310 -40);
PAINT MONO (2310 -40);
FORCEPROP 0 LASTPIN (2300 0) $PN DB85
J 0
(2310 10);
DISPLAY 0.680851 (2310 10);
PAINT MONO (2310 10);
FORCEPROP 0 LASTPIN (2300 50) $PN CY87
J 0
(2310 60);
DISPLAY 0.680851 (2310 60);
PAINT MONO (2310 60);
FORCEPROP 0 LASTPIN (2300 100) $PN CV85
J 0
(2310 110);
DISPLAY 0.680851 (2310 110);
PAINT MONO (2310 110);
FORCEPROP 0 LASTPIN (2300 150) $PN CT87
J 0
(2310 160);
DISPLAY 0.680851 (2310 160);
PAINT MONO (2310 160);
FORCEPROP 0 LASTPIN (2300 200) $PN CP85
J 0
(2310 210);
DISPLAY 0.680851 (2310 210);
PAINT MONO (2310 210);
FORCEPROP 0 LASTPIN (2300 300) $PN ED87
J 0
(2310 310);
DISPLAY 0.680851 (2310 310);
PAINT MONO (2310 310);
FORCEPROP 0 LASTPIN (2300 350) $PN EC86
J 0
(2310 360);
DISPLAY 0.680851 (2310 360);
PAINT MONO (2310 360);
FORCEPROP 0 LASTPIN (2300 400) $PN EA86
J 0
(2310 410);
DISPLAY 0.680851 (2310 410);
PAINT MONO (2310 410);
FORCEPROP 0 LASTPIN (2300 450) $PN DW86
J 0
(2310 460);
DISPLAY 0.680851 (2310 460);
PAINT MONO (2310 460);
FORCEPROP 0 LASTPIN (2300 500) $PN DU86
J 0
(2310 510);
DISPLAY 0.680851 (2310 510);
PAINT MONO (2310 510);
FORCEPROP 0 LASTPIN (2300 550) $PN DR86
J 0
(2310 560);
DISPLAY 0.680851 (2310 560);
PAINT MONO (2310 560);
FORCEPROP 0 LASTPIN (2300 600) $PN DN86
J 0
(2310 610);
DISPLAY 0.680851 (2310 610);
PAINT MONO (2310 610);
FORCEPROP 0 LASTPIN (2300 650) $PN DL86
J 0
(2310 660);
DISPLAY 0.680851 (2310 660);
PAINT MONO (2310 660);
FORCEPROP 0 LASTPIN (2300 700) $PN DJ86
J 0
(2310 710);
DISPLAY 0.680851 (2310 710);
PAINT MONO (2310 710);
FORCEPROP 0 LASTPIN (2300 750) $PN DG86
J 0
(2310 760);
DISPLAY 0.680851 (2310 760);
PAINT MONO (2310 760);
FORCEPROP 0 LASTPIN (2300 800) $PN DE86
J 0
(2310 810);
DISPLAY 0.680851 (2310 810);
PAINT MONO (2310 810);
FORCEPROP 0 LASTPIN (2300 850) $PN DC86
J 0
(2310 860);
DISPLAY 0.680851 (2310 860);
PAINT MONO (2310 860);
FORCEPROP 0 LASTPIN (2300 900) $PN DA86
J 0
(2310 910);
DISPLAY 0.680851 (2310 910);
PAINT MONO (2310 910);
FORCEPROP 0 LASTPIN (2300 950) $PN CW86
J 0
(2310 960);
DISPLAY 0.680851 (2310 960);
PAINT MONO (2310 960);
FORCEPROP 0 LASTPIN (2300 1000) $PN CU86
J 0
(2310 1010);
DISPLAY 0.680851 (2310 1010);
PAINT MONO (2310 1010);
FORCEPROP 0 LASTPIN (2300 1050) $PN CR86
J 0
(2310 1060);
DISPLAY 0.680851 (2310 1060);
PAINT MONO (2310 1060);
FORCEPROP 1 LAST CDS_LMAN_SYM_OUTLINE -1050,950,1050,-950
J 0
(1100 250);
DISPLAY 0.468085 (1100 250);
PAINT GREEN (1100 250);
DISPLAY INVISIBLE (1100 250);
FORCEPROP 1 LAST NEEDS_NO_SIZE TRUE
J 0
(1100 250);
DISPLAY 0.723404 (1100 250);
PAINT GREEN (1100 250);
DISPLAY INVISIBLE (1100 250);
FORCEPROP 2 LAST CDS_LIB pure_quanta
J 0
(1100 250);
DISPLAY INVISIBLE (1100 250);
FORCEPROP 2 LAST CDS_LOCATION U2
J 0
(50 1525);
DISPLAY 1.021277 (50 1525);
DISPLAY INVISIBLE (50 1525);
FORCEPROP 0 LAST $SEC 20
J 0
(50 1525);
DISPLAY 0.680851 (50 1525);
PAINT MONO (50 1525);
DISPLAY INVISIBLE (50 1525);
FORCEPROP 2 LAST CDS_SEC 20
J 0
(50 1525);
DISPLAY 1.021277 (50 1525);
DISPLAY INVISIBLE (50 1525);
FORCEPROP 1 LAST PATH I140
J 0
(1100 250);
DISPLAY 0.723404 (1100 250);
PAINT GREEN (1100 250);
DISPLAY INVISIBLE (1100 250);
FORCEADD OFFPAGE..1
(-1850 3850);
FORCEPROP 2 LAST $XR1 137 
J 0
(-2222 3850);
DISPLAY 0.638298 (-2222 3850);
PAINT MONO (-2222 3850);
FORCEPROP 2 LAST $XR0 136 
J 0
(-2102 3850);
DISPLAY 0.638298 (-2102 3850);
PAINT MONO (-2102 3850);
FORCEPROP 2 LAST CDS_LIB standard
J 0
(-1850 3850);
DISPLAY INVISIBLE (-1850 3850);
FORCEPROP 1 LAST OFFPAGE TRUE
J 0
(-1525 3725);
DISPLAY 0.872340 (-1525 3725);
DISPLAY INVISIBLE (-1525 3725);
FORCEPROP 1 LAST COMMENT_BODY TRUE
J 0
(-1725 3750);
DISPLAY 0.872340 (-1725 3750);
PAINT GREEN (-1725 3750);
DISPLAY INVISIBLE (-1725 3750);
FORCEPROP 2 LAST PATH I181
J 0
(-2125 3900);
DISPLAY 1.021277 (-2125 3900);
DISPLAY INVISIBLE (-2125 3900);
FORCEADD OFFPAGE..1
(-1850 3000);
FORCEPROP 2 LAST $XR1 137 
J 0
(-2222 3000);
DISPLAY 0.638298 (-2222 3000);
PAINT MONO (-2222 3000);
FORCEPROP 2 LAST $XR0 136 
J 0
(-2102 3000);
DISPLAY 0.638298 (-2102 3000);
PAINT MONO (-2102 3000);
FORCEPROP 2 LAST CDS_LIB standard
J 0
(-1850 3000);
DISPLAY INVISIBLE (-1850 3000);
FORCEPROP 1 LAST OFFPAGE TRUE
J 0
(-1525 2875);
DISPLAY 0.872340 (-1525 2875);
DISPLAY INVISIBLE (-1525 2875);
FORCEPROP 1 LAST COMMENT_BODY TRUE
J 0
(-1725 2900);
DISPLAY 0.872340 (-1725 2900);
PAINT GREEN (-1725 2900);
DISPLAY INVISIBLE (-1725 2900);
FORCEPROP 2 LAST PATH I182
J 0
(-2125 3050);
DISPLAY 1.021277 (-2125 3050);
DISPLAY INVISIBLE (-2125 3050);
FORCEADD OFFPAGE..1
(-1825 225);
FORCEPROP 2 LAST $XR1 137 
J 0
(-2197 225);
DISPLAY 0.638298 (-2197 225);
PAINT MONO (-2197 225);
FORCEPROP 2 LAST $XR0 136 
J 0
(-2077 225);
DISPLAY 0.638298 (-2077 225);
PAINT MONO (-2077 225);
FORCEPROP 2 LAST CDS_LIB standard
J 0
(-1825 225);
PAINT MONO (-1825 225);
DISPLAY INVISIBLE (-1825 225);
FORCEPROP 1 LAST OFFPAGE TRUE
J 0
(-1500 100);
DISPLAY 0.872340 (-1500 100);
DISPLAY INVISIBLE (-1500 100);
FORCEPROP 1 LAST COMMENT_BODY TRUE
J 0
(-1700 125);
DISPLAY 0.872340 (-1700 125);
PAINT GREEN (-1700 125);
DISPLAY INVISIBLE (-1700 125);
FORCEPROP 2 LAST PATH I251
J 0
(-2075 275);
DISPLAY 1.021277 (-2075 275);
DISPLAY INVISIBLE (-2075 275);
FORCEADD OFFPAGE..1
(-1825 1075);
FORCEPROP 2 LAST $XR1 137 
J 0
(-2197 1075);
DISPLAY 0.638298 (-2197 1075);
PAINT MONO (-2197 1075);
FORCEPROP 2 LAST $XR0 136 
J 0
(-2077 1075);
DISPLAY 0.638298 (-2077 1075);
PAINT MONO (-2077 1075);
FORCEPROP 2 LAST CDS_LIB standard
J 0
(-1825 1075);
PAINT MONO (-1825 1075);
DISPLAY INVISIBLE (-1825 1075);
FORCEPROP 1 LAST OFFPAGE TRUE
J 0
(-1500 950);
DISPLAY 0.872340 (-1500 950);
DISPLAY INVISIBLE (-1500 950);
FORCEPROP 1 LAST COMMENT_BODY TRUE
J 0
(-1700 975);
DISPLAY 0.872340 (-1700 975);
PAINT GREEN (-1700 975);
DISPLAY INVISIBLE (-1700 975);
FORCEPROP 2 LAST PATH I252
J 0
(-2075 1125);
DISPLAY 1.021277 (-2075 1125);
DISPLAY INVISIBLE (-2075 1125);
FORCEADD TAP..1
R 2
(-575 -550);
FORCEPROP 3 LASTPIN (-525 -550) SIG_NAME P5E_CPU0_PE3_RX_DN<0>
J 0
(-515 -540);
DISPLAY 0.659574 (-515 -540);
PAINT MONO (-515 -540);
DISPLAY INVISIBLE (-515 -540);
FORCEPROP 1 LASTPIN (-525 -550) BN 0
J 2
(-513 -542);
DISPLAY 0.680851 (-513 -542);
PAINT GREEN (-513 -542);
FORCEPROP 2 LAST CDS_LIB standard
J 0
(-575 -550);
DISPLAY INVISIBLE (-575 -550);
FORCEPROP 1 LAST BODY_TYPE PLUMBING
J 2
(-575 -500);
DISPLAY 0.872340 (-575 -500);
PAINT GREEN (-575 -500);
DISPLAY INVISIBLE (-575 -500);
FORCEPROP 1 LAST HDL_TAP TRUE
J 2
(-900 -675);
DISPLAY 0.872340 (-900 -675);
DISPLAY INVISIBLE (-900 -675);
FORCEPROP 1 LAST PATH I253
J 2
(-573 -550);
DISPLAY 0.872340 (-573 -550);
PAINT GREEN (-573 -550);
DISPLAY INVISIBLE (-573 -550);
FORCEADD TAP..1
R 2
(-575 -450);
FORCEPROP 3 LASTPIN (-525 -450) SIG_NAME P5E_CPU0_PE3_RX_DN<2>
J 0
(-515 -440);
DISPLAY 0.659574 (-515 -440);
PAINT MONO (-515 -440);
DISPLAY INVISIBLE (-515 -440);
FORCEPROP 1 LASTPIN (-525 -450) BN 2
J 2
(-513 -442);
DISPLAY 0.680851 (-513 -442);
PAINT GREEN (-513 -442);
FORCEPROP 2 LAST CDS_LIB standard
J 0
(-575 -450);
DISPLAY INVISIBLE (-575 -450);
FORCEPROP 1 LAST BODY_TYPE PLUMBING
J 2
(-575 -400);
DISPLAY 0.872340 (-575 -400);
PAINT GREEN (-575 -400);
DISPLAY INVISIBLE (-575 -400);
FORCEPROP 1 LAST HDL_TAP TRUE
J 2
(-900 -575);
DISPLAY 0.872340 (-900 -575);
DISPLAY INVISIBLE (-900 -575);
FORCEPROP 1 LAST PATH I254
J 2
(-573 -450);
DISPLAY 0.872340 (-573 -450);
PAINT GREEN (-573 -450);
DISPLAY INVISIBLE (-573 -450);
FORCEADD TAP..1
R 2
(-575 -500);
FORCEPROP 3 LASTPIN (-525 -500) SIG_NAME P5E_CPU0_PE3_RX_DN<1>
J 0
(-515 -490);
DISPLAY 0.659574 (-515 -490);
PAINT MONO (-515 -490);
DISPLAY INVISIBLE (-515 -490);
FORCEPROP 1 LASTPIN (-525 -500) BN 1
J 2
(-513 -492);
DISPLAY 0.680851 (-513 -492);
PAINT GREEN (-513 -492);
FORCEPROP 2 LAST CDS_LIB standard
J 0
(-575 -500);
DISPLAY INVISIBLE (-575 -500);
FORCEPROP 1 LAST BODY_TYPE PLUMBING
J 2
(-575 -450);
DISPLAY 0.872340 (-575 -450);
PAINT GREEN (-575 -450);
DISPLAY INVISIBLE (-575 -450);
FORCEPROP 1 LAST HDL_TAP TRUE
J 2
(-900 -625);
DISPLAY 0.872340 (-900 -625);
DISPLAY INVISIBLE (-900 -625);
FORCEPROP 1 LAST PATH I255
J 2
(-573 -500);
DISPLAY 0.872340 (-573 -500);
PAINT GREEN (-573 -500);
DISPLAY INVISIBLE (-573 -500);
FORCEADD TAP..1
R 2
(-575 -400);
FORCEPROP 3 LASTPIN (-525 -400) SIG_NAME P5E_CPU0_PE3_RX_DN<3>
J 0
(-515 -390);
DISPLAY 0.659574 (-515 -390);
PAINT MONO (-515 -390);
DISPLAY INVISIBLE (-515 -390);
FORCEPROP 1 LASTPIN (-525 -400) BN 3
J 2
(-513 -392);
DISPLAY 0.680851 (-513 -392);
PAINT GREEN (-513 -392);
FORCEPROP 2 LAST CDS_LIB standard
J 0
(-575 -400);
DISPLAY INVISIBLE (-575 -400);
FORCEPROP 1 LAST BODY_TYPE PLUMBING
J 2
(-575 -350);
DISPLAY 0.872340 (-575 -350);
PAINT GREEN (-575 -350);
DISPLAY INVISIBLE (-575 -350);
FORCEPROP 1 LAST HDL_TAP TRUE
J 2
(-900 -525);
DISPLAY 0.872340 (-900 -525);
DISPLAY INVISIBLE (-900 -525);
FORCEPROP 1 LAST PATH I256
J 2
(-573 -400);
DISPLAY 0.872340 (-573 -400);
PAINT GREEN (-573 -400);
DISPLAY INVISIBLE (-573 -400);
FORCEADD TAP..1
R 2
(-575 -350);
FORCEPROP 3 LASTPIN (-525 -350) SIG_NAME P5E_CPU0_PE3_RX_DN<4>
J 0
(-515 -340);
DISPLAY 0.659574 (-515 -340);
PAINT MONO (-515 -340);
DISPLAY INVISIBLE (-515 -340);
FORCEPROP 1 LASTPIN (-525 -350) BN 4
J 2
(-513 -342);
DISPLAY 0.680851 (-513 -342);
PAINT GREEN (-513 -342);
FORCEPROP 2 LAST CDS_LIB standard
J 0
(-575 -350);
DISPLAY INVISIBLE (-575 -350);
FORCEPROP 1 LAST BODY_TYPE PLUMBING
J 2
(-575 -300);
DISPLAY 0.872340 (-575 -300);
PAINT GREEN (-575 -300);
DISPLAY INVISIBLE (-575 -300);
FORCEPROP 1 LAST HDL_TAP TRUE
J 2
(-900 -475);
DISPLAY 0.872340 (-900 -475);
DISPLAY INVISIBLE (-900 -475);
FORCEPROP 1 LAST PATH I257
J 2
(-573 -350);
DISPLAY 0.872340 (-573 -350);
PAINT GREEN (-573 -350);
DISPLAY INVISIBLE (-573 -350);
FORCEADD TAP..1
R 2
(-575 -300);
FORCEPROP 3 LASTPIN (-525 -300) SIG_NAME P5E_CPU0_PE3_RX_DN<5>
J 0
(-515 -290);
DISPLAY 0.659574 (-515 -290);
PAINT MONO (-515 -290);
DISPLAY INVISIBLE (-515 -290);
FORCEPROP 1 LASTPIN (-525 -300) BN 5
J 2
(-513 -292);
DISPLAY 0.680851 (-513 -292);
PAINT GREEN (-513 -292);
FORCEPROP 2 LAST CDS_LIB standard
J 0
(-575 -300);
DISPLAY INVISIBLE (-575 -300);
FORCEPROP 1 LAST BODY_TYPE PLUMBING
J 2
(-575 -250);
DISPLAY 0.872340 (-575 -250);
PAINT GREEN (-575 -250);
DISPLAY INVISIBLE (-575 -250);
FORCEPROP 1 LAST HDL_TAP TRUE
J 2
(-900 -425);
DISPLAY 0.872340 (-900 -425);
DISPLAY INVISIBLE (-900 -425);
FORCEPROP 1 LAST PATH I258
J 2
(-573 -300);
DISPLAY 0.872340 (-573 -300);
PAINT GREEN (-573 -300);
DISPLAY INVISIBLE (-573 -300);
FORCEADD TAP..1
R 2
(-575 -200);
FORCEPROP 3 LASTPIN (-525 -200) SIG_NAME P5E_CPU0_PE3_RX_DN<7>
J 0
(-515 -190);
DISPLAY 0.659574 (-515 -190);
PAINT MONO (-515 -190);
DISPLAY INVISIBLE (-515 -190);
FORCEPROP 1 LASTPIN (-525 -200) BN 7
J 2
(-513 -192);
DISPLAY 0.680851 (-513 -192);
PAINT GREEN (-513 -192);
FORCEPROP 2 LAST CDS_LIB standard
J 0
(-575 -200);
DISPLAY INVISIBLE (-575 -200);
FORCEPROP 1 LAST BODY_TYPE PLUMBING
J 2
(-575 -150);
DISPLAY 0.872340 (-575 -150);
PAINT GREEN (-575 -150);
DISPLAY INVISIBLE (-575 -150);
FORCEPROP 1 LAST HDL_TAP TRUE
J 2
(-900 -325);
DISPLAY 0.872340 (-900 -325);
DISPLAY INVISIBLE (-900 -325);
FORCEPROP 1 LAST PATH I259
J 2
(-573 -200);
DISPLAY 0.872340 (-573 -200);
PAINT GREEN (-573 -200);
DISPLAY INVISIBLE (-573 -200);
FORCEADD TAP..1
R 2
(-575 -250);
FORCEPROP 3 LASTPIN (-525 -250) SIG_NAME P5E_CPU0_PE3_RX_DN<6>
J 0
(-515 -240);
DISPLAY 0.659574 (-515 -240);
PAINT MONO (-515 -240);
DISPLAY INVISIBLE (-515 -240);
FORCEPROP 1 LASTPIN (-525 -250) BN 6
J 2
(-513 -242);
DISPLAY 0.680851 (-513 -242);
PAINT GREEN (-513 -242);
FORCEPROP 2 LAST CDS_LIB standard
J 0
(-575 -250);
DISPLAY INVISIBLE (-575 -250);
FORCEPROP 1 LAST BODY_TYPE PLUMBING
J 2
(-575 -200);
DISPLAY 0.872340 (-575 -200);
PAINT GREEN (-575 -200);
DISPLAY INVISIBLE (-575 -200);
FORCEPROP 1 LAST HDL_TAP TRUE
J 2
(-900 -375);
DISPLAY 0.872340 (-900 -375);
DISPLAY INVISIBLE (-900 -375);
FORCEPROP 1 LAST PATH I260
J 2
(-573 -250);
DISPLAY 0.872340 (-573 -250);
PAINT GREEN (-573 -250);
DISPLAY INVISIBLE (-573 -250);
FORCEADD TAP..1
R 2
(-575 -150);
FORCEPROP 3 LASTPIN (-525 -150) SIG_NAME P5E_CPU0_PE3_RX_DN<8>
J 0
(-515 -140);
DISPLAY 0.659574 (-515 -140);
PAINT MONO (-515 -140);
DISPLAY INVISIBLE (-515 -140);
FORCEPROP 1 LASTPIN (-525 -150) BN 8
J 2
(-513 -142);
DISPLAY 0.680851 (-513 -142);
PAINT GREEN (-513 -142);
FORCEPROP 2 LAST CDS_LIB standard
J 0
(-575 -150);
DISPLAY INVISIBLE (-575 -150);
FORCEPROP 1 LAST BODY_TYPE PLUMBING
J 2
(-575 -100);
DISPLAY 0.872340 (-575 -100);
PAINT GREEN (-575 -100);
DISPLAY INVISIBLE (-575 -100);
FORCEPROP 1 LAST HDL_TAP TRUE
J 2
(-900 -275);
DISPLAY 0.872340 (-900 -275);
DISPLAY INVISIBLE (-900 -275);
FORCEPROP 1 LAST PATH I261
J 2
(-573 -150);
DISPLAY 0.872340 (-573 -150);
PAINT GREEN (-573 -150);
DISPLAY INVISIBLE (-573 -150);
FORCEADD TAP..1
R 2
(-575 -100);
FORCEPROP 3 LASTPIN (-525 -100) SIG_NAME P5E_CPU0_PE3_RX_DN<9>
J 0
(-515 -90);
DISPLAY 0.659574 (-515 -90);
PAINT MONO (-515 -90);
DISPLAY INVISIBLE (-515 -90);
FORCEPROP 1 LASTPIN (-525 -100) BN 9
J 2
(-513 -92);
DISPLAY 0.680851 (-513 -92);
PAINT GREEN (-513 -92);
FORCEPROP 2 LAST CDS_LIB standard
J 0
(-575 -100);
DISPLAY INVISIBLE (-575 -100);
FORCEPROP 1 LAST BODY_TYPE PLUMBING
J 2
(-575 -50);
DISPLAY 0.872340 (-575 -50);
PAINT GREEN (-575 -50);
DISPLAY INVISIBLE (-575 -50);
FORCEPROP 1 LAST HDL_TAP TRUE
J 2
(-900 -225);
DISPLAY 0.872340 (-900 -225);
DISPLAY INVISIBLE (-900 -225);
FORCEPROP 1 LAST PATH I262
J 2
(-573 -100);
DISPLAY 0.872340 (-573 -100);
PAINT GREEN (-573 -100);
DISPLAY INVISIBLE (-573 -100);
FORCEADD TAP..1
R 2
(-575 -50);
FORCEPROP 3 LASTPIN (-525 -50) SIG_NAME P5E_CPU0_PE3_RX_DN<10>
J 0
(-515 -40);
DISPLAY 0.659574 (-515 -40);
PAINT MONO (-515 -40);
DISPLAY INVISIBLE (-515 -40);
FORCEPROP 1 LASTPIN (-525 -50) BN 10
J 2
(-513 -42);
DISPLAY 0.680851 (-513 -42);
PAINT GREEN (-513 -42);
FORCEPROP 2 LAST CDS_LIB standard
J 0
(-575 -50);
DISPLAY INVISIBLE (-575 -50);
FORCEPROP 1 LAST BODY_TYPE PLUMBING
J 2
(-575 0);
DISPLAY 0.872340 (-575 0);
PAINT GREEN (-575 0);
DISPLAY INVISIBLE (-575 0);
FORCEPROP 1 LAST HDL_TAP TRUE
J 2
(-900 -175);
DISPLAY 0.872340 (-900 -175);
DISPLAY INVISIBLE (-900 -175);
FORCEPROP 1 LAST PATH I263
J 2
(-573 -50);
DISPLAY 0.872340 (-573 -50);
PAINT GREEN (-573 -50);
DISPLAY INVISIBLE (-573 -50);
FORCEADD TAP..1
R 2
(-575 0);
FORCEPROP 3 LASTPIN (-525 0) SIG_NAME P5E_CPU0_PE3_RX_DN<11>
J 0
(-515 10);
DISPLAY 0.659574 (-515 10);
PAINT MONO (-515 10);
DISPLAY INVISIBLE (-515 10);
FORCEPROP 1 LASTPIN (-525 0) BN 11
J 2
(-513 8);
DISPLAY 0.680851 (-513 8);
PAINT GREEN (-513 8);
FORCEPROP 2 LAST CDS_LIB standard
J 0
(-575 0);
DISPLAY INVISIBLE (-575 0);
FORCEPROP 1 LAST BODY_TYPE PLUMBING
J 2
(-575 50);
DISPLAY 0.872340 (-575 50);
PAINT GREEN (-575 50);
DISPLAY INVISIBLE (-575 50);
FORCEPROP 1 LAST HDL_TAP TRUE
J 2
(-900 -125);
DISPLAY 0.872340 (-900 -125);
DISPLAY INVISIBLE (-900 -125);
FORCEPROP 1 LAST PATH I264
J 2
(-573 0);
DISPLAY 0.872340 (-573 0);
PAINT GREEN (-573 0);
DISPLAY INVISIBLE (-573 0);
FORCEADD TAP..1
R 2
(-575 50);
FORCEPROP 3 LASTPIN (-525 50) SIG_NAME P5E_CPU0_PE3_RX_DN<12>
J 0
(-515 60);
DISPLAY 0.659574 (-515 60);
PAINT MONO (-515 60);
DISPLAY INVISIBLE (-515 60);
FORCEPROP 1 LASTPIN (-525 50) BN 12
J 2
(-513 58);
DISPLAY 0.680851 (-513 58);
PAINT GREEN (-513 58);
FORCEPROP 2 LAST CDS_LIB standard
J 0
(-575 50);
DISPLAY INVISIBLE (-575 50);
FORCEPROP 1 LAST BODY_TYPE PLUMBING
J 2
(-575 100);
DISPLAY 0.872340 (-575 100);
PAINT GREEN (-575 100);
DISPLAY INVISIBLE (-575 100);
FORCEPROP 1 LAST HDL_TAP TRUE
J 2
(-900 -75);
DISPLAY 0.872340 (-900 -75);
DISPLAY INVISIBLE (-900 -75);
FORCEPROP 1 LAST PATH I265
J 2
(-573 50);
DISPLAY 0.872340 (-573 50);
PAINT GREEN (-573 50);
DISPLAY INVISIBLE (-573 50);
FORCEADD TAP..1
R 2
(-575 150);
FORCEPROP 3 LASTPIN (-525 150) SIG_NAME P5E_CPU0_PE3_RX_DN<14>
J 0
(-515 160);
DISPLAY 0.659574 (-515 160);
PAINT MONO (-515 160);
DISPLAY INVISIBLE (-515 160);
FORCEPROP 1 LASTPIN (-525 150) BN 14
J 2
(-513 158);
DISPLAY 0.680851 (-513 158);
PAINT GREEN (-513 158);
FORCEPROP 2 LAST CDS_LIB standard
J 0
(-575 150);
DISPLAY INVISIBLE (-575 150);
FORCEPROP 1 LAST BODY_TYPE PLUMBING
J 2
(-575 200);
DISPLAY 0.872340 (-575 200);
PAINT GREEN (-575 200);
DISPLAY INVISIBLE (-575 200);
FORCEPROP 1 LAST HDL_TAP TRUE
J 2
(-900 25);
DISPLAY 0.872340 (-900 25);
DISPLAY INVISIBLE (-900 25);
FORCEPROP 1 LAST PATH I266
J 2
(-573 150);
DISPLAY 0.872340 (-573 150);
PAINT GREEN (-573 150);
DISPLAY INVISIBLE (-573 150);
FORCEADD TAP..1
R 2
(-575 100);
FORCEPROP 3 LASTPIN (-525 100) SIG_NAME P5E_CPU0_PE3_RX_DN<13>
J 0
(-515 110);
DISPLAY 0.659574 (-515 110);
PAINT MONO (-515 110);
DISPLAY INVISIBLE (-515 110);
FORCEPROP 1 LASTPIN (-525 100) BN 13
J 2
(-513 108);
DISPLAY 0.680851 (-513 108);
PAINT GREEN (-513 108);
FORCEPROP 2 LAST CDS_LIB standard
J 0
(-575 100);
DISPLAY INVISIBLE (-575 100);
FORCEPROP 1 LAST BODY_TYPE PLUMBING
J 2
(-575 150);
DISPLAY 0.872340 (-575 150);
PAINT GREEN (-575 150);
DISPLAY INVISIBLE (-575 150);
FORCEPROP 1 LAST HDL_TAP TRUE
J 2
(-900 -25);
DISPLAY 0.872340 (-900 -25);
DISPLAY INVISIBLE (-900 -25);
FORCEPROP 1 LAST PATH I267
J 2
(-573 100);
DISPLAY 0.872340 (-573 100);
PAINT GREEN (-573 100);
DISPLAY INVISIBLE (-573 100);
FORCEADD TAP..1
R 2
(-575 200);
FORCEPROP 3 LASTPIN (-525 200) SIG_NAME P5E_CPU0_PE3_RX_DN<15>
J 0
(-515 210);
DISPLAY 0.659574 (-515 210);
PAINT MONO (-515 210);
DISPLAY INVISIBLE (-515 210);
FORCEPROP 1 LASTPIN (-525 200) BN 15
J 2
(-513 208);
DISPLAY 0.680851 (-513 208);
PAINT GREEN (-513 208);
FORCEPROP 2 LAST CDS_LIB standard
J 0
(-575 200);
DISPLAY INVISIBLE (-575 200);
FORCEPROP 1 LAST BODY_TYPE PLUMBING
J 2
(-575 250);
DISPLAY 0.872340 (-575 250);
PAINT GREEN (-575 250);
DISPLAY INVISIBLE (-575 250);
FORCEPROP 1 LAST HDL_TAP TRUE
J 2
(-900 75);
DISPLAY 0.872340 (-900 75);
DISPLAY INVISIBLE (-900 75);
FORCEPROP 1 LAST PATH I268
J 2
(-573 200);
DISPLAY 0.872340 (-573 200);
PAINT GREEN (-573 200);
DISPLAY INVISIBLE (-573 200);
FORCEADD TAP..1
R 2
(-575 300);
FORCEPROP 3 LASTPIN (-525 300) SIG_NAME P5E_CPU0_PE3_RX_DP<0>
J 0
(-515 310);
DISPLAY 0.659574 (-515 310);
PAINT MONO (-515 310);
DISPLAY INVISIBLE (-515 310);
FORCEPROP 1 LASTPIN (-525 300) BN 0
J 2
(-513 308);
DISPLAY 0.680851 (-513 308);
PAINT GREEN (-513 308);
FORCEPROP 2 LAST CDS_LIB standard
J 0
(-575 300);
DISPLAY INVISIBLE (-575 300);
FORCEPROP 1 LAST BODY_TYPE PLUMBING
J 2
(-575 350);
DISPLAY 0.872340 (-575 350);
PAINT GREEN (-575 350);
DISPLAY INVISIBLE (-575 350);
FORCEPROP 1 LAST HDL_TAP TRUE
J 2
(-900 175);
DISPLAY 0.872340 (-900 175);
DISPLAY INVISIBLE (-900 175);
FORCEPROP 1 LAST PATH I269
J 2
(-573 300);
DISPLAY 0.872340 (-573 300);
PAINT GREEN (-573 300);
DISPLAY INVISIBLE (-573 300);
FORCEADD TAP..1
R 2
(-575 350);
FORCEPROP 3 LASTPIN (-525 350) SIG_NAME P5E_CPU0_PE3_RX_DP<1>
J 0
(-515 360);
DISPLAY 0.659574 (-515 360);
PAINT MONO (-515 360);
DISPLAY INVISIBLE (-515 360);
FORCEPROP 1 LASTPIN (-525 350) BN 1
J 2
(-513 358);
DISPLAY 0.680851 (-513 358);
PAINT GREEN (-513 358);
FORCEPROP 2 LAST CDS_LIB standard
J 0
(-575 350);
DISPLAY INVISIBLE (-575 350);
FORCEPROP 1 LAST BODY_TYPE PLUMBING
J 2
(-575 400);
DISPLAY 0.872340 (-575 400);
PAINT GREEN (-575 400);
DISPLAY INVISIBLE (-575 400);
FORCEPROP 1 LAST HDL_TAP TRUE
J 2
(-900 225);
DISPLAY 0.872340 (-900 225);
DISPLAY INVISIBLE (-900 225);
FORCEPROP 1 LAST PATH I270
J 2
(-573 350);
DISPLAY 0.872340 (-573 350);
PAINT GREEN (-573 350);
DISPLAY INVISIBLE (-573 350);
FORCEADD TAP..1
R 2
(-575 450);
FORCEPROP 3 LASTPIN (-525 450) SIG_NAME P5E_CPU0_PE3_RX_DP<3>
J 0
(-515 460);
DISPLAY 0.659574 (-515 460);
PAINT MONO (-515 460);
DISPLAY INVISIBLE (-515 460);
FORCEPROP 1 LASTPIN (-525 450) BN 3
J 2
(-513 458);
DISPLAY 0.680851 (-513 458);
PAINT GREEN (-513 458);
FORCEPROP 2 LAST CDS_LIB standard
J 0
(-575 450);
DISPLAY INVISIBLE (-575 450);
FORCEPROP 1 LAST BODY_TYPE PLUMBING
J 2
(-575 500);
DISPLAY 0.872340 (-575 500);
PAINT GREEN (-575 500);
DISPLAY INVISIBLE (-575 500);
FORCEPROP 1 LAST HDL_TAP TRUE
J 2
(-900 325);
DISPLAY 0.872340 (-900 325);
DISPLAY INVISIBLE (-900 325);
FORCEPROP 1 LAST PATH I271
J 2
(-573 450);
DISPLAY 0.872340 (-573 450);
PAINT GREEN (-573 450);
DISPLAY INVISIBLE (-573 450);
FORCEADD TAP..1
R 2
(-575 400);
FORCEPROP 3 LASTPIN (-525 400) SIG_NAME P5E_CPU0_PE3_RX_DP<2>
J 0
(-515 410);
DISPLAY 0.659574 (-515 410);
PAINT MONO (-515 410);
DISPLAY INVISIBLE (-515 410);
FORCEPROP 1 LASTPIN (-525 400) BN 2
J 2
(-513 408);
DISPLAY 0.680851 (-513 408);
PAINT GREEN (-513 408);
FORCEPROP 2 LAST CDS_LIB standard
J 0
(-575 400);
DISPLAY INVISIBLE (-575 400);
FORCEPROP 1 LAST BODY_TYPE PLUMBING
J 2
(-575 450);
DISPLAY 0.872340 (-575 450);
PAINT GREEN (-575 450);
DISPLAY INVISIBLE (-575 450);
FORCEPROP 1 LAST HDL_TAP TRUE
J 2
(-900 275);
DISPLAY 0.872340 (-900 275);
DISPLAY INVISIBLE (-900 275);
FORCEPROP 1 LAST PATH I272
J 2
(-573 400);
DISPLAY 0.872340 (-573 400);
PAINT GREEN (-573 400);
DISPLAY INVISIBLE (-573 400);
FORCEADD TAP..1
R 2
(-575 500);
FORCEPROP 3 LASTPIN (-525 500) SIG_NAME P5E_CPU0_PE3_RX_DP<4>
J 0
(-515 510);
DISPLAY 0.659574 (-515 510);
PAINT MONO (-515 510);
DISPLAY INVISIBLE (-515 510);
FORCEPROP 1 LASTPIN (-525 500) BN 4
J 2
(-513 508);
DISPLAY 0.680851 (-513 508);
PAINT GREEN (-513 508);
FORCEPROP 2 LAST CDS_LIB standard
J 0
(-575 500);
DISPLAY INVISIBLE (-575 500);
FORCEPROP 1 LAST BODY_TYPE PLUMBING
J 2
(-575 550);
DISPLAY 0.872340 (-575 550);
PAINT GREEN (-575 550);
DISPLAY INVISIBLE (-575 550);
FORCEPROP 1 LAST HDL_TAP TRUE
J 2
(-900 375);
DISPLAY 0.872340 (-900 375);
DISPLAY INVISIBLE (-900 375);
FORCEPROP 1 LAST PATH I273
J 2
(-573 500);
DISPLAY 0.872340 (-573 500);
PAINT GREEN (-573 500);
DISPLAY INVISIBLE (-573 500);
FORCEADD TAP..1
R 2
(-575 550);
FORCEPROP 3 LASTPIN (-525 550) SIG_NAME P5E_CPU0_PE3_RX_DP<5>
J 0
(-515 560);
DISPLAY 0.659574 (-515 560);
PAINT MONO (-515 560);
DISPLAY INVISIBLE (-515 560);
FORCEPROP 1 LASTPIN (-525 550) BN 5
J 2
(-513 558);
DISPLAY 0.680851 (-513 558);
PAINT GREEN (-513 558);
FORCEPROP 2 LAST CDS_LIB standard
J 0
(-575 550);
DISPLAY INVISIBLE (-575 550);
FORCEPROP 1 LAST BODY_TYPE PLUMBING
J 2
(-575 600);
DISPLAY 0.872340 (-575 600);
PAINT GREEN (-575 600);
DISPLAY INVISIBLE (-575 600);
FORCEPROP 1 LAST HDL_TAP TRUE
J 2
(-900 425);
DISPLAY 0.872340 (-900 425);
DISPLAY INVISIBLE (-900 425);
FORCEPROP 1 LAST PATH I274
J 2
(-573 550);
DISPLAY 0.872340 (-573 550);
PAINT GREEN (-573 550);
DISPLAY INVISIBLE (-573 550);
FORCEADD TAP..1
R 2
(-575 600);
FORCEPROP 3 LASTPIN (-525 600) SIG_NAME P5E_CPU0_PE3_RX_DP<6>
J 0
(-515 610);
DISPLAY 0.659574 (-515 610);
PAINT MONO (-515 610);
DISPLAY INVISIBLE (-515 610);
FORCEPROP 1 LASTPIN (-525 600) BN 6
J 2
(-513 608);
DISPLAY 0.680851 (-513 608);
PAINT GREEN (-513 608);
FORCEPROP 2 LAST CDS_LIB standard
J 0
(-575 600);
DISPLAY INVISIBLE (-575 600);
FORCEPROP 1 LAST BODY_TYPE PLUMBING
J 2
(-575 650);
DISPLAY 0.872340 (-575 650);
PAINT GREEN (-575 650);
DISPLAY INVISIBLE (-575 650);
FORCEPROP 1 LAST HDL_TAP TRUE
J 2
(-900 475);
DISPLAY 0.872340 (-900 475);
DISPLAY INVISIBLE (-900 475);
FORCEPROP 1 LAST PATH I275
J 2
(-573 600);
DISPLAY 0.872340 (-573 600);
PAINT GREEN (-573 600);
DISPLAY INVISIBLE (-573 600);
FORCEADD TAP..1
R 2
(-575 700);
FORCEPROP 3 LASTPIN (-525 700) SIG_NAME P5E_CPU0_PE3_RX_DP<8>
J 0
(-515 710);
DISPLAY 0.659574 (-515 710);
PAINT MONO (-515 710);
DISPLAY INVISIBLE (-515 710);
FORCEPROP 1 LASTPIN (-525 700) BN 8
J 2
(-513 708);
DISPLAY 0.680851 (-513 708);
PAINT GREEN (-513 708);
FORCEPROP 2 LAST CDS_LIB standard
J 0
(-575 700);
DISPLAY INVISIBLE (-575 700);
FORCEPROP 1 LAST BODY_TYPE PLUMBING
J 2
(-575 750);
DISPLAY 0.872340 (-575 750);
PAINT GREEN (-575 750);
DISPLAY INVISIBLE (-575 750);
FORCEPROP 1 LAST HDL_TAP TRUE
J 2
(-900 575);
DISPLAY 0.872340 (-900 575);
DISPLAY INVISIBLE (-900 575);
FORCEPROP 1 LAST PATH I276
J 2
(-573 700);
DISPLAY 0.872340 (-573 700);
PAINT GREEN (-573 700);
DISPLAY INVISIBLE (-573 700);
FORCEADD TAP..1
R 2
(-575 650);
FORCEPROP 3 LASTPIN (-525 650) SIG_NAME P5E_CPU0_PE3_RX_DP<7>
J 0
(-515 660);
DISPLAY 0.659574 (-515 660);
PAINT MONO (-515 660);
DISPLAY INVISIBLE (-515 660);
FORCEPROP 1 LASTPIN (-525 650) BN 7
J 2
(-513 658);
DISPLAY 0.680851 (-513 658);
PAINT GREEN (-513 658);
FORCEPROP 2 LAST CDS_LIB standard
J 0
(-575 650);
DISPLAY INVISIBLE (-575 650);
FORCEPROP 1 LAST BODY_TYPE PLUMBING
J 2
(-575 700);
DISPLAY 0.872340 (-575 700);
PAINT GREEN (-575 700);
DISPLAY INVISIBLE (-575 700);
FORCEPROP 1 LAST HDL_TAP TRUE
J 2
(-900 525);
DISPLAY 0.872340 (-900 525);
DISPLAY INVISIBLE (-900 525);
FORCEPROP 1 LAST PATH I277
J 2
(-573 650);
DISPLAY 0.872340 (-573 650);
PAINT GREEN (-573 650);
DISPLAY INVISIBLE (-573 650);
FORCEADD TAP..1
R 2
(-575 750);
FORCEPROP 3 LASTPIN (-525 750) SIG_NAME P5E_CPU0_PE3_RX_DP<9>
J 0
(-515 760);
DISPLAY 0.659574 (-515 760);
PAINT MONO (-515 760);
DISPLAY INVISIBLE (-515 760);
FORCEPROP 1 LASTPIN (-525 750) BN 9
J 2
(-513 758);
DISPLAY 0.680851 (-513 758);
PAINT GREEN (-513 758);
FORCEPROP 2 LAST CDS_LIB standard
J 0
(-575 750);
DISPLAY INVISIBLE (-575 750);
FORCEPROP 1 LAST BODY_TYPE PLUMBING
J 2
(-575 800);
DISPLAY 0.872340 (-575 800);
PAINT GREEN (-575 800);
DISPLAY INVISIBLE (-575 800);
FORCEPROP 1 LAST HDL_TAP TRUE
J 2
(-900 625);
DISPLAY 0.872340 (-900 625);
DISPLAY INVISIBLE (-900 625);
FORCEPROP 1 LAST PATH I278
J 2
(-573 750);
DISPLAY 0.872340 (-573 750);
PAINT GREEN (-573 750);
DISPLAY INVISIBLE (-573 750);
FORCEADD TAP..1
R 2
(-575 800);
FORCEPROP 3 LASTPIN (-525 800) SIG_NAME P5E_CPU0_PE3_RX_DP<10>
J 0
(-515 810);
DISPLAY 0.659574 (-515 810);
PAINT MONO (-515 810);
DISPLAY INVISIBLE (-515 810);
FORCEPROP 1 LASTPIN (-525 800) BN 10
J 2
(-513 808);
DISPLAY 0.680851 (-513 808);
PAINT GREEN (-513 808);
FORCEPROP 2 LAST CDS_LIB standard
J 0
(-575 800);
DISPLAY INVISIBLE (-575 800);
FORCEPROP 1 LAST BODY_TYPE PLUMBING
J 2
(-575 850);
DISPLAY 0.872340 (-575 850);
PAINT GREEN (-575 850);
DISPLAY INVISIBLE (-575 850);
FORCEPROP 1 LAST HDL_TAP TRUE
J 2
(-900 675);
DISPLAY 0.872340 (-900 675);
DISPLAY INVISIBLE (-900 675);
FORCEPROP 1 LAST PATH I279
J 2
(-573 800);
DISPLAY 0.872340 (-573 800);
PAINT GREEN (-573 800);
DISPLAY INVISIBLE (-573 800);
FORCEADD TAP..1
R 2
(-575 850);
FORCEPROP 3 LASTPIN (-525 850) SIG_NAME P5E_CPU0_PE3_RX_DP<11>
J 0
(-515 860);
DISPLAY 0.659574 (-515 860);
PAINT MONO (-515 860);
DISPLAY INVISIBLE (-515 860);
FORCEPROP 1 LASTPIN (-525 850) BN 11
J 2
(-513 858);
DISPLAY 0.680851 (-513 858);
PAINT GREEN (-513 858);
FORCEPROP 2 LAST CDS_LIB standard
J 0
(-575 850);
DISPLAY INVISIBLE (-575 850);
FORCEPROP 1 LAST BODY_TYPE PLUMBING
J 2
(-575 900);
DISPLAY 0.872340 (-575 900);
PAINT GREEN (-575 900);
DISPLAY INVISIBLE (-575 900);
FORCEPROP 1 LAST HDL_TAP TRUE
J 2
(-900 725);
DISPLAY 0.872340 (-900 725);
DISPLAY INVISIBLE (-900 725);
FORCEPROP 1 LAST PATH I280
J 2
(-573 850);
DISPLAY 0.872340 (-573 850);
PAINT GREEN (-573 850);
DISPLAY INVISIBLE (-573 850);
FORCEADD TAP..1
R 2
(-575 900);
FORCEPROP 3 LASTPIN (-525 900) SIG_NAME P5E_CPU0_PE3_RX_DP<12>
J 0
(-515 910);
DISPLAY 0.659574 (-515 910);
PAINT MONO (-515 910);
DISPLAY INVISIBLE (-515 910);
FORCEPROP 1 LASTPIN (-525 900) BN 12
J 2
(-513 908);
DISPLAY 0.680851 (-513 908);
PAINT GREEN (-513 908);
FORCEPROP 2 LAST CDS_LIB standard
J 0
(-575 900);
DISPLAY INVISIBLE (-575 900);
FORCEPROP 1 LAST BODY_TYPE PLUMBING
J 2
(-575 950);
DISPLAY 0.872340 (-575 950);
PAINT GREEN (-575 950);
DISPLAY INVISIBLE (-575 950);
FORCEPROP 1 LAST HDL_TAP TRUE
J 2
(-900 775);
DISPLAY 0.872340 (-900 775);
DISPLAY INVISIBLE (-900 775);
FORCEPROP 1 LAST PATH I281
J 2
(-573 900);
DISPLAY 0.872340 (-573 900);
PAINT GREEN (-573 900);
DISPLAY INVISIBLE (-573 900);
FORCEADD TAP..1
R 2
(-575 950);
FORCEPROP 3 LASTPIN (-525 950) SIG_NAME P5E_CPU0_PE3_RX_DP<13>
J 0
(-515 960);
DISPLAY 0.659574 (-515 960);
PAINT MONO (-515 960);
DISPLAY INVISIBLE (-515 960);
FORCEPROP 1 LASTPIN (-525 950) BN 13
J 2
(-513 958);
DISPLAY 0.680851 (-513 958);
PAINT GREEN (-513 958);
FORCEPROP 2 LAST CDS_LIB standard
J 0
(-575 950);
DISPLAY INVISIBLE (-575 950);
FORCEPROP 1 LAST BODY_TYPE PLUMBING
J 2
(-575 1000);
DISPLAY 0.872340 (-575 1000);
PAINT GREEN (-575 1000);
DISPLAY INVISIBLE (-575 1000);
FORCEPROP 1 LAST HDL_TAP TRUE
J 2
(-900 825);
DISPLAY 0.872340 (-900 825);
DISPLAY INVISIBLE (-900 825);
FORCEPROP 1 LAST PATH I282
J 2
(-573 950);
DISPLAY 0.872340 (-573 950);
PAINT GREEN (-573 950);
DISPLAY INVISIBLE (-573 950);
FORCEADD TAP..1
R 2
(-575 1000);
FORCEPROP 3 LASTPIN (-525 1000) SIG_NAME P5E_CPU0_PE3_RX_DP<14>
J 0
(-515 1010);
DISPLAY 0.659574 (-515 1010);
PAINT MONO (-515 1010);
DISPLAY INVISIBLE (-515 1010);
FORCEPROP 1 LASTPIN (-525 1000) BN 14
J 2
(-513 1008);
DISPLAY 0.680851 (-513 1008);
PAINT GREEN (-513 1008);
FORCEPROP 2 LAST CDS_LIB standard
J 0
(-575 1000);
DISPLAY INVISIBLE (-575 1000);
FORCEPROP 1 LAST BODY_TYPE PLUMBING
J 2
(-575 1050);
DISPLAY 0.872340 (-575 1050);
PAINT GREEN (-575 1050);
DISPLAY INVISIBLE (-575 1050);
FORCEPROP 1 LAST HDL_TAP TRUE
J 2
(-900 875);
DISPLAY 0.872340 (-900 875);
DISPLAY INVISIBLE (-900 875);
FORCEPROP 1 LAST PATH I283
J 2
(-573 1000);
DISPLAY 0.872340 (-573 1000);
PAINT GREEN (-573 1000);
DISPLAY INVISIBLE (-573 1000);
FORCEADD TAP..1
R 2
(-575 1050);
FORCEPROP 3 LASTPIN (-525 1050) SIG_NAME P5E_CPU0_PE3_RX_DP<15>
J 0
(-515 1060);
DISPLAY 0.659574 (-515 1060);
PAINT MONO (-515 1060);
DISPLAY INVISIBLE (-515 1060);
FORCEPROP 1 LASTPIN (-525 1050) BN 15
J 2
(-513 1058);
DISPLAY 0.680851 (-513 1058);
PAINT GREEN (-513 1058);
FORCEPROP 2 LAST CDS_LIB standard
J 0
(-575 1050);
DISPLAY INVISIBLE (-575 1050);
FORCEPROP 1 LAST BODY_TYPE PLUMBING
J 2
(-575 1100);
DISPLAY 0.872340 (-575 1100);
PAINT GREEN (-575 1100);
DISPLAY INVISIBLE (-575 1100);
FORCEPROP 1 LAST HDL_TAP TRUE
J 2
(-900 925);
DISPLAY 0.872340 (-900 925);
DISPLAY INVISIBLE (-900 925);
FORCEPROP 1 LAST PATH I284
J 2
(-573 1050);
DISPLAY 0.872340 (-573 1050);
PAINT GREEN (-573 1050);
DISPLAY INVISIBLE (-573 1050);
FORCEADD TAP..1
(2825 -550);
FORCEPROP 3 LASTPIN (2775 -550) SIG_NAME P5E_CPU0_PE3_TX_DN<0>
J 0
(2785 -540);
DISPLAY 0.659574 (2785 -540);
PAINT MONO (2785 -540);
DISPLAY INVISIBLE (2785 -540);
FORCEPROP 1 LASTPIN (2775 -550) BN 0
J 0
(2763 -542);
DISPLAY 0.680851 (2763 -542);
PAINT GREEN (2763 -542);
FORCEPROP 2 LAST CDS_LIB standard
J 0
(2825 -550);
PAINT MONO (2825 -550);
DISPLAY INVISIBLE (2825 -550);
FORCEPROP 1 LAST BODY_TYPE PLUMBING
J 0
(2825 -500);
DISPLAY 0.872340 (2825 -500);
PAINT GREEN (2825 -500);
DISPLAY INVISIBLE (2825 -500);
FORCEPROP 1 LAST HDL_TAP TRUE
J 0
(3150 -675);
DISPLAY 0.872340 (3150 -675);
DISPLAY INVISIBLE (3150 -675);
FORCEPROP 1 LAST PATH I285
J 0
(2823 -550);
DISPLAY 0.872340 (2823 -550);
PAINT GREEN (2823 -550);
DISPLAY INVISIBLE (2823 -550);
FORCEADD TAP..1
(2825 -500);
FORCEPROP 3 LASTPIN (2775 -500) SIG_NAME P5E_CPU0_PE3_TX_DN<1>
J 0
(2785 -490);
DISPLAY 0.659574 (2785 -490);
PAINT MONO (2785 -490);
DISPLAY INVISIBLE (2785 -490);
FORCEPROP 1 LASTPIN (2775 -500) BN 1
J 0
(2763 -492);
DISPLAY 0.680851 (2763 -492);
PAINT GREEN (2763 -492);
FORCEPROP 2 LAST CDS_LIB standard
J 0
(2825 -500);
PAINT MONO (2825 -500);
DISPLAY INVISIBLE (2825 -500);
FORCEPROP 1 LAST BODY_TYPE PLUMBING
J 0
(2825 -450);
DISPLAY 0.872340 (2825 -450);
PAINT GREEN (2825 -450);
DISPLAY INVISIBLE (2825 -450);
FORCEPROP 1 LAST HDL_TAP TRUE
J 0
(3150 -625);
DISPLAY 0.872340 (3150 -625);
DISPLAY INVISIBLE (3150 -625);
FORCEPROP 1 LAST PATH I286
J 0
(2823 -500);
DISPLAY 0.872340 (2823 -500);
PAINT GREEN (2823 -500);
DISPLAY INVISIBLE (2823 -500);
FORCEADD TAP..1
(2825 -400);
FORCEPROP 3 LASTPIN (2775 -400) SIG_NAME P5E_CPU0_PE3_TX_DN<3>
J 0
(2785 -390);
DISPLAY 0.659574 (2785 -390);
PAINT MONO (2785 -390);
DISPLAY INVISIBLE (2785 -390);
FORCEPROP 1 LASTPIN (2775 -400) BN 3
J 0
(2763 -392);
DISPLAY 0.680851 (2763 -392);
PAINT GREEN (2763 -392);
FORCEPROP 2 LAST CDS_LIB standard
J 0
(2825 -400);
PAINT MONO (2825 -400);
DISPLAY INVISIBLE (2825 -400);
FORCEPROP 1 LAST BODY_TYPE PLUMBING
J 0
(2825 -350);
DISPLAY 0.872340 (2825 -350);
PAINT GREEN (2825 -350);
DISPLAY INVISIBLE (2825 -350);
FORCEPROP 1 LAST HDL_TAP TRUE
J 0
(3150 -525);
DISPLAY 0.872340 (3150 -525);
DISPLAY INVISIBLE (3150 -525);
FORCEPROP 1 LAST PATH I287
J 0
(2823 -400);
DISPLAY 0.872340 (2823 -400);
PAINT GREEN (2823 -400);
DISPLAY INVISIBLE (2823 -400);
FORCEADD TAP..1
(2825 -450);
FORCEPROP 3 LASTPIN (2775 -450) SIG_NAME P5E_CPU0_PE3_TX_DN<2>
J 0
(2785 -440);
DISPLAY 0.659574 (2785 -440);
PAINT MONO (2785 -440);
DISPLAY INVISIBLE (2785 -440);
FORCEPROP 1 LASTPIN (2775 -450) BN 2
J 0
(2763 -442);
DISPLAY 0.680851 (2763 -442);
PAINT GREEN (2763 -442);
FORCEPROP 2 LAST CDS_LIB standard
J 0
(2825 -450);
PAINT MONO (2825 -450);
DISPLAY INVISIBLE (2825 -450);
FORCEPROP 1 LAST BODY_TYPE PLUMBING
J 0
(2825 -400);
DISPLAY 0.872340 (2825 -400);
PAINT GREEN (2825 -400);
DISPLAY INVISIBLE (2825 -400);
FORCEPROP 1 LAST HDL_TAP TRUE
J 0
(3150 -575);
DISPLAY 0.872340 (3150 -575);
DISPLAY INVISIBLE (3150 -575);
FORCEPROP 1 LAST PATH I288
J 0
(2823 -450);
DISPLAY 0.872340 (2823 -450);
PAINT GREEN (2823 -450);
DISPLAY INVISIBLE (2823 -450);
FORCEADD TAP..1
(2825 -350);
FORCEPROP 3 LASTPIN (2775 -350) SIG_NAME P5E_CPU0_PE3_TX_DN<4>
J 0
(2785 -340);
DISPLAY 0.659574 (2785 -340);
PAINT MONO (2785 -340);
DISPLAY INVISIBLE (2785 -340);
FORCEPROP 1 LASTPIN (2775 -350) BN 4
J 0
(2763 -342);
DISPLAY 0.680851 (2763 -342);
PAINT GREEN (2763 -342);
FORCEPROP 2 LAST CDS_LIB standard
J 0
(2825 -350);
PAINT MONO (2825 -350);
DISPLAY INVISIBLE (2825 -350);
FORCEPROP 1 LAST BODY_TYPE PLUMBING
J 0
(2825 -300);
DISPLAY 0.872340 (2825 -300);
PAINT GREEN (2825 -300);
DISPLAY INVISIBLE (2825 -300);
FORCEPROP 1 LAST HDL_TAP TRUE
J 0
(3150 -475);
DISPLAY 0.872340 (3150 -475);
DISPLAY INVISIBLE (3150 -475);
FORCEPROP 1 LAST PATH I289
J 0
(2823 -350);
DISPLAY 0.872340 (2823 -350);
PAINT GREEN (2823 -350);
DISPLAY INVISIBLE (2823 -350);
FORCEADD TAP..1
(2825 -250);
FORCEPROP 3 LASTPIN (2775 -250) SIG_NAME P5E_CPU0_PE3_TX_DN<6>
J 0
(2785 -240);
DISPLAY 0.659574 (2785 -240);
PAINT MONO (2785 -240);
DISPLAY INVISIBLE (2785 -240);
FORCEPROP 1 LASTPIN (2775 -250) BN 6
J 0
(2763 -242);
DISPLAY 0.680851 (2763 -242);
PAINT GREEN (2763 -242);
FORCEPROP 2 LAST CDS_LIB standard
J 0
(2825 -250);
PAINT MONO (2825 -250);
DISPLAY INVISIBLE (2825 -250);
FORCEPROP 1 LAST BODY_TYPE PLUMBING
J 0
(2825 -200);
DISPLAY 0.872340 (2825 -200);
PAINT GREEN (2825 -200);
DISPLAY INVISIBLE (2825 -200);
FORCEPROP 1 LAST HDL_TAP TRUE
J 0
(3150 -375);
DISPLAY 0.872340 (3150 -375);
DISPLAY INVISIBLE (3150 -375);
FORCEPROP 1 LAST PATH I290
J 0
(2823 -250);
DISPLAY 0.872340 (2823 -250);
PAINT GREEN (2823 -250);
DISPLAY INVISIBLE (2823 -250);
FORCEADD TAP..1
(2825 -300);
FORCEPROP 3 LASTPIN (2775 -300) SIG_NAME P5E_CPU0_PE3_TX_DN<5>
J 0
(2785 -290);
DISPLAY 0.659574 (2785 -290);
PAINT MONO (2785 -290);
DISPLAY INVISIBLE (2785 -290);
FORCEPROP 1 LASTPIN (2775 -300) BN 5
J 0
(2763 -292);
DISPLAY 0.680851 (2763 -292);
PAINT GREEN (2763 -292);
FORCEPROP 2 LAST CDS_LIB standard
J 0
(2825 -300);
PAINT MONO (2825 -300);
DISPLAY INVISIBLE (2825 -300);
FORCEPROP 1 LAST BODY_TYPE PLUMBING
J 0
(2825 -250);
DISPLAY 0.872340 (2825 -250);
PAINT GREEN (2825 -250);
DISPLAY INVISIBLE (2825 -250);
FORCEPROP 1 LAST HDL_TAP TRUE
J 0
(3150 -425);
DISPLAY 0.872340 (3150 -425);
DISPLAY INVISIBLE (3150 -425);
FORCEPROP 1 LAST PATH I291
J 0
(2823 -300);
DISPLAY 0.872340 (2823 -300);
PAINT GREEN (2823 -300);
DISPLAY INVISIBLE (2823 -300);
FORCEADD TAP..1
(2825 -150);
FORCEPROP 3 LASTPIN (2775 -150) SIG_NAME P5E_CPU0_PE3_TX_DN<8>
J 0
(2785 -140);
DISPLAY 0.659574 (2785 -140);
PAINT MONO (2785 -140);
DISPLAY INVISIBLE (2785 -140);
FORCEPROP 1 LASTPIN (2775 -150) BN 8
J 0
(2763 -142);
DISPLAY 0.680851 (2763 -142);
PAINT GREEN (2763 -142);
FORCEPROP 2 LAST CDS_LIB standard
J 0
(2825 -150);
PAINT MONO (2825 -150);
DISPLAY INVISIBLE (2825 -150);
FORCEPROP 1 LAST BODY_TYPE PLUMBING
J 0
(2825 -100);
DISPLAY 0.872340 (2825 -100);
PAINT GREEN (2825 -100);
DISPLAY INVISIBLE (2825 -100);
FORCEPROP 1 LAST HDL_TAP TRUE
J 0
(3150 -275);
DISPLAY 0.872340 (3150 -275);
DISPLAY INVISIBLE (3150 -275);
FORCEPROP 1 LAST PATH I292
J 0
(2823 -150);
DISPLAY 0.872340 (2823 -150);
PAINT GREEN (2823 -150);
DISPLAY INVISIBLE (2823 -150);
FORCEADD TAP..1
(2825 -200);
FORCEPROP 3 LASTPIN (2775 -200) SIG_NAME P5E_CPU0_PE3_TX_DN<7>
J 0
(2785 -190);
DISPLAY 0.659574 (2785 -190);
PAINT MONO (2785 -190);
DISPLAY INVISIBLE (2785 -190);
FORCEPROP 1 LASTPIN (2775 -200) BN 7
J 0
(2763 -192);
DISPLAY 0.680851 (2763 -192);
PAINT GREEN (2763 -192);
FORCEPROP 2 LAST CDS_LIB standard
J 0
(2825 -200);
PAINT MONO (2825 -200);
DISPLAY INVISIBLE (2825 -200);
FORCEPROP 1 LAST BODY_TYPE PLUMBING
J 0
(2825 -150);
DISPLAY 0.872340 (2825 -150);
PAINT GREEN (2825 -150);
DISPLAY INVISIBLE (2825 -150);
FORCEPROP 1 LAST HDL_TAP TRUE
J 0
(3150 -325);
DISPLAY 0.872340 (3150 -325);
DISPLAY INVISIBLE (3150 -325);
FORCEPROP 1 LAST PATH I293
J 0
(2823 -200);
DISPLAY 0.872340 (2823 -200);
PAINT GREEN (2823 -200);
DISPLAY INVISIBLE (2823 -200);
FORCEADD TAP..1
(2825 -100);
FORCEPROP 3 LASTPIN (2775 -100) SIG_NAME P5E_CPU0_PE3_TX_DN<9>
J 0
(2785 -90);
DISPLAY 0.659574 (2785 -90);
PAINT MONO (2785 -90);
DISPLAY INVISIBLE (2785 -90);
FORCEPROP 1 LASTPIN (2775 -100) BN 9
J 0
(2763 -92);
DISPLAY 0.680851 (2763 -92);
PAINT GREEN (2763 -92);
FORCEPROP 2 LAST CDS_LIB standard
J 0
(2825 -100);
DISPLAY INVISIBLE (2825 -100);
FORCEPROP 1 LAST BODY_TYPE PLUMBING
J 0
(2825 -50);
DISPLAY 0.872340 (2825 -50);
PAINT GREEN (2825 -50);
DISPLAY INVISIBLE (2825 -50);
FORCEPROP 1 LAST HDL_TAP TRUE
J 0
(3150 -225);
DISPLAY 0.872340 (3150 -225);
DISPLAY INVISIBLE (3150 -225);
FORCEPROP 1 LAST PATH I294
J 0
(2823 -100);
DISPLAY 0.872340 (2823 -100);
PAINT GREEN (2823 -100);
DISPLAY INVISIBLE (2823 -100);
FORCEADD TAP..1
(2825 -50);
FORCEPROP 3 LASTPIN (2775 -50) SIG_NAME P5E_CPU0_PE3_TX_DN<10>
J 0
(2785 -40);
DISPLAY 0.659574 (2785 -40);
PAINT MONO (2785 -40);
DISPLAY INVISIBLE (2785 -40);
FORCEPROP 1 LASTPIN (2775 -50) BN 10
J 0
(2763 -42);
DISPLAY 0.680851 (2763 -42);
PAINT GREEN (2763 -42);
FORCEPROP 2 LAST CDS_LIB standard
J 0
(2825 -50);
DISPLAY INVISIBLE (2825 -50);
FORCEPROP 1 LAST BODY_TYPE PLUMBING
J 0
(2825 0);
DISPLAY 0.872340 (2825 0);
PAINT GREEN (2825 0);
DISPLAY INVISIBLE (2825 0);
FORCEPROP 1 LAST HDL_TAP TRUE
J 0
(3150 -175);
DISPLAY 0.872340 (3150 -175);
DISPLAY INVISIBLE (3150 -175);
FORCEPROP 1 LAST PATH I295
J 0
(2823 -50);
DISPLAY 0.872340 (2823 -50);
PAINT GREEN (2823 -50);
DISPLAY INVISIBLE (2823 -50);
FORCEADD TAP..1
(2825 0);
FORCEPROP 3 LASTPIN (2775 0) SIG_NAME P5E_CPU0_PE3_TX_DN<11>
J 0
(2785 10);
DISPLAY 0.659574 (2785 10);
PAINT MONO (2785 10);
DISPLAY INVISIBLE (2785 10);
FORCEPROP 1 LASTPIN (2775 0) BN 11
J 0
(2763 8);
DISPLAY 0.680851 (2763 8);
PAINT GREEN (2763 8);
FORCEPROP 2 LAST CDS_LIB standard
J 0
(2825 0);
DISPLAY INVISIBLE (2825 0);
FORCEPROP 1 LAST BODY_TYPE PLUMBING
J 0
(2825 50);
DISPLAY 0.872340 (2825 50);
PAINT GREEN (2825 50);
DISPLAY INVISIBLE (2825 50);
FORCEPROP 1 LAST HDL_TAP TRUE
J 0
(3150 -125);
DISPLAY 0.872340 (3150 -125);
DISPLAY INVISIBLE (3150 -125);
FORCEPROP 1 LAST PATH I296
J 0
(2823 0);
DISPLAY 0.872340 (2823 0);
PAINT GREEN (2823 0);
DISPLAY INVISIBLE (2823 0);
FORCEADD TAP..1
(2825 50);
FORCEPROP 3 LASTPIN (2775 50) SIG_NAME P5E_CPU0_PE3_TX_DN<12>
J 0
(2785 60);
DISPLAY 0.659574 (2785 60);
PAINT MONO (2785 60);
DISPLAY INVISIBLE (2785 60);
FORCEPROP 1 LASTPIN (2775 50) BN 12
J 0
(2763 58);
DISPLAY 0.680851 (2763 58);
PAINT GREEN (2763 58);
FORCEPROP 2 LAST CDS_LIB standard
J 0
(2825 50);
DISPLAY INVISIBLE (2825 50);
FORCEPROP 1 LAST BODY_TYPE PLUMBING
J 0
(2825 100);
DISPLAY 0.872340 (2825 100);
PAINT GREEN (2825 100);
DISPLAY INVISIBLE (2825 100);
FORCEPROP 1 LAST HDL_TAP TRUE
J 0
(3150 -75);
DISPLAY 0.872340 (3150 -75);
DISPLAY INVISIBLE (3150 -75);
FORCEPROP 1 LAST PATH I297
J 0
(2823 50);
DISPLAY 0.872340 (2823 50);
PAINT GREEN (2823 50);
DISPLAY INVISIBLE (2823 50);
FORCEADD TAP..1
(2825 100);
FORCEPROP 3 LASTPIN (2775 100) SIG_NAME P5E_CPU0_PE3_TX_DN<13>
J 0
(2785 110);
DISPLAY 0.659574 (2785 110);
PAINT MONO (2785 110);
DISPLAY INVISIBLE (2785 110);
FORCEPROP 1 LASTPIN (2775 100) BN 13
J 0
(2763 108);
DISPLAY 0.680851 (2763 108);
PAINT GREEN (2763 108);
FORCEPROP 2 LAST CDS_LIB standard
J 0
(2825 100);
DISPLAY INVISIBLE (2825 100);
FORCEPROP 1 LAST BODY_TYPE PLUMBING
J 0
(2825 150);
DISPLAY 0.872340 (2825 150);
PAINT GREEN (2825 150);
DISPLAY INVISIBLE (2825 150);
FORCEPROP 1 LAST HDL_TAP TRUE
J 0
(3150 -25);
DISPLAY 0.872340 (3150 -25);
DISPLAY INVISIBLE (3150 -25);
FORCEPROP 1 LAST PATH I298
J 0
(2823 100);
DISPLAY 0.872340 (2823 100);
PAINT GREEN (2823 100);
DISPLAY INVISIBLE (2823 100);
FORCEADD TAP..1
(2825 150);
FORCEPROP 3 LASTPIN (2775 150) SIG_NAME P5E_CPU0_PE3_TX_DN<14>
J 0
(2785 160);
DISPLAY 0.659574 (2785 160);
PAINT MONO (2785 160);
DISPLAY INVISIBLE (2785 160);
FORCEPROP 1 LASTPIN (2775 150) BN 14
J 0
(2763 158);
DISPLAY 0.680851 (2763 158);
PAINT GREEN (2763 158);
FORCEPROP 2 LAST CDS_LIB standard
J 0
(2825 150);
DISPLAY INVISIBLE (2825 150);
FORCEPROP 1 LAST BODY_TYPE PLUMBING
J 0
(2825 200);
DISPLAY 0.872340 (2825 200);
PAINT GREEN (2825 200);
DISPLAY INVISIBLE (2825 200);
FORCEPROP 1 LAST HDL_TAP TRUE
J 0
(3150 25);
DISPLAY 0.872340 (3150 25);
DISPLAY INVISIBLE (3150 25);
FORCEPROP 1 LAST PATH I299
J 0
(2823 150);
DISPLAY 0.872340 (2823 150);
PAINT GREEN (2823 150);
DISPLAY INVISIBLE (2823 150);
FORCEADD TAP..1
(2825 200);
FORCEPROP 3 LASTPIN (2775 200) SIG_NAME P5E_CPU0_PE3_TX_DN<15>
J 0
(2785 210);
DISPLAY 0.659574 (2785 210);
PAINT MONO (2785 210);
DISPLAY INVISIBLE (2785 210);
FORCEPROP 1 LASTPIN (2775 200) BN 15
J 0
(2763 208);
DISPLAY 0.680851 (2763 208);
PAINT GREEN (2763 208);
FORCEPROP 2 LAST CDS_LIB standard
J 0
(2825 200);
DISPLAY INVISIBLE (2825 200);
FORCEPROP 1 LAST BODY_TYPE PLUMBING
J 0
(2825 250);
DISPLAY 0.872340 (2825 250);
PAINT GREEN (2825 250);
DISPLAY INVISIBLE (2825 250);
FORCEPROP 1 LAST HDL_TAP TRUE
J 0
(3150 75);
DISPLAY 0.872340 (3150 75);
DISPLAY INVISIBLE (3150 75);
FORCEPROP 1 LAST PATH I300
J 0
(2823 200);
DISPLAY 0.872340 (2823 200);
PAINT GREEN (2823 200);
DISPLAY INVISIBLE (2823 200);
FORCEADD TAP..1
(2825 300);
FORCEPROP 3 LASTPIN (2775 300) SIG_NAME P5E_CPU0_PE3_TX_DP<0>
J 0
(2785 310);
DISPLAY 0.659574 (2785 310);
PAINT MONO (2785 310);
DISPLAY INVISIBLE (2785 310);
FORCEPROP 1 LASTPIN (2775 300) BN 0
J 0
(2763 308);
DISPLAY 0.680851 (2763 308);
PAINT GREEN (2763 308);
FORCEPROP 2 LAST CDS_LIB standard
J 0
(2825 300);
PAINT MONO (2825 300);
DISPLAY INVISIBLE (2825 300);
FORCEPROP 1 LAST BODY_TYPE PLUMBING
J 0
(2825 350);
DISPLAY 0.872340 (2825 350);
PAINT GREEN (2825 350);
DISPLAY INVISIBLE (2825 350);
FORCEPROP 1 LAST HDL_TAP TRUE
J 0
(3150 175);
DISPLAY 0.872340 (3150 175);
DISPLAY INVISIBLE (3150 175);
FORCEPROP 1 LAST PATH I301
J 0
(2823 300);
DISPLAY 0.872340 (2823 300);
PAINT GREEN (2823 300);
DISPLAY INVISIBLE (2823 300);
FORCEADD TAP..1
(2825 350);
FORCEPROP 3 LASTPIN (2775 350) SIG_NAME P5E_CPU0_PE3_TX_DP<1>
J 0
(2785 360);
DISPLAY 0.659574 (2785 360);
PAINT MONO (2785 360);
DISPLAY INVISIBLE (2785 360);
FORCEPROP 1 LASTPIN (2775 350) BN 1
J 0
(2763 358);
DISPLAY 0.680851 (2763 358);
PAINT GREEN (2763 358);
FORCEPROP 2 LAST CDS_LIB standard
J 0
(2825 350);
PAINT MONO (2825 350);
DISPLAY INVISIBLE (2825 350);
FORCEPROP 1 LAST BODY_TYPE PLUMBING
J 0
(2825 400);
DISPLAY 0.872340 (2825 400);
PAINT GREEN (2825 400);
DISPLAY INVISIBLE (2825 400);
FORCEPROP 1 LAST HDL_TAP TRUE
J 0
(3150 225);
DISPLAY 0.872340 (3150 225);
DISPLAY INVISIBLE (3150 225);
FORCEPROP 1 LAST PATH I302
J 0
(2823 350);
DISPLAY 0.872340 (2823 350);
PAINT GREEN (2823 350);
DISPLAY INVISIBLE (2823 350);
FORCEADD TAP..1
(2825 400);
FORCEPROP 3 LASTPIN (2775 400) SIG_NAME P5E_CPU0_PE3_TX_DP<2>
J 0
(2785 410);
DISPLAY 0.659574 (2785 410);
PAINT MONO (2785 410);
DISPLAY INVISIBLE (2785 410);
FORCEPROP 1 LASTPIN (2775 400) BN 2
J 0
(2763 408);
DISPLAY 0.680851 (2763 408);
PAINT GREEN (2763 408);
FORCEPROP 2 LAST CDS_LIB standard
J 0
(2825 400);
PAINT MONO (2825 400);
DISPLAY INVISIBLE (2825 400);
FORCEPROP 1 LAST BODY_TYPE PLUMBING
J 0
(2825 450);
DISPLAY 0.872340 (2825 450);
PAINT GREEN (2825 450);
DISPLAY INVISIBLE (2825 450);
FORCEPROP 1 LAST HDL_TAP TRUE
J 0
(3150 275);
DISPLAY 0.872340 (3150 275);
DISPLAY INVISIBLE (3150 275);
FORCEPROP 1 LAST PATH I303
J 0
(2823 400);
DISPLAY 0.872340 (2823 400);
PAINT GREEN (2823 400);
DISPLAY INVISIBLE (2823 400);
FORCEADD TAP..1
(2825 500);
FORCEPROP 3 LASTPIN (2775 500) SIG_NAME P5E_CPU0_PE3_TX_DP<4>
J 0
(2785 510);
DISPLAY 0.659574 (2785 510);
PAINT MONO (2785 510);
DISPLAY INVISIBLE (2785 510);
FORCEPROP 1 LASTPIN (2775 500) BN 4
J 0
(2763 508);
DISPLAY 0.680851 (2763 508);
PAINT GREEN (2763 508);
FORCEPROP 2 LAST CDS_LIB standard
J 0
(2825 500);
PAINT MONO (2825 500);
DISPLAY INVISIBLE (2825 500);
FORCEPROP 1 LAST BODY_TYPE PLUMBING
J 0
(2825 550);
DISPLAY 0.872340 (2825 550);
PAINT GREEN (2825 550);
DISPLAY INVISIBLE (2825 550);
FORCEPROP 1 LAST HDL_TAP TRUE
J 0
(3150 375);
DISPLAY 0.872340 (3150 375);
DISPLAY INVISIBLE (3150 375);
FORCEPROP 1 LAST PATH I304
J 0
(2823 500);
DISPLAY 0.872340 (2823 500);
PAINT GREEN (2823 500);
DISPLAY INVISIBLE (2823 500);
FORCEADD TAP..1
(2825 450);
FORCEPROP 3 LASTPIN (2775 450) SIG_NAME P5E_CPU0_PE3_TX_DP<3>
J 0
(2785 460);
DISPLAY 0.659574 (2785 460);
PAINT MONO (2785 460);
DISPLAY INVISIBLE (2785 460);
FORCEPROP 1 LASTPIN (2775 450) BN 3
J 0
(2763 458);
DISPLAY 0.680851 (2763 458);
PAINT GREEN (2763 458);
FORCEPROP 2 LAST CDS_LIB standard
J 0
(2825 450);
PAINT MONO (2825 450);
DISPLAY INVISIBLE (2825 450);
FORCEPROP 1 LAST BODY_TYPE PLUMBING
J 0
(2825 500);
DISPLAY 0.872340 (2825 500);
PAINT GREEN (2825 500);
DISPLAY INVISIBLE (2825 500);
FORCEPROP 1 LAST HDL_TAP TRUE
J 0
(3150 325);
DISPLAY 0.872340 (3150 325);
DISPLAY INVISIBLE (3150 325);
FORCEPROP 1 LAST PATH I305
J 0
(2823 450);
DISPLAY 0.872340 (2823 450);
PAINT GREEN (2823 450);
DISPLAY INVISIBLE (2823 450);
FORCEADD TAP..1
(2825 550);
FORCEPROP 3 LASTPIN (2775 550) SIG_NAME P5E_CPU0_PE3_TX_DP<5>
J 0
(2785 560);
DISPLAY 0.659574 (2785 560);
PAINT MONO (2785 560);
DISPLAY INVISIBLE (2785 560);
FORCEPROP 1 LASTPIN (2775 550) BN 5
J 0
(2763 558);
DISPLAY 0.680851 (2763 558);
PAINT GREEN (2763 558);
FORCEPROP 2 LAST CDS_LIB standard
J 0
(2825 550);
PAINT MONO (2825 550);
DISPLAY INVISIBLE (2825 550);
FORCEPROP 1 LAST BODY_TYPE PLUMBING
J 0
(2825 600);
DISPLAY 0.872340 (2825 600);
PAINT GREEN (2825 600);
DISPLAY INVISIBLE (2825 600);
FORCEPROP 1 LAST HDL_TAP TRUE
J 0
(3150 425);
DISPLAY 0.872340 (3150 425);
DISPLAY INVISIBLE (3150 425);
FORCEPROP 1 LAST PATH I306
J 0
(2823 550);
DISPLAY 0.872340 (2823 550);
PAINT GREEN (2823 550);
DISPLAY INVISIBLE (2823 550);
FORCEADD TAP..1
(2825 600);
FORCEPROP 3 LASTPIN (2775 600) SIG_NAME P5E_CPU0_PE3_TX_DP<6>
J 0
(2785 610);
DISPLAY 0.659574 (2785 610);
PAINT MONO (2785 610);
DISPLAY INVISIBLE (2785 610);
FORCEPROP 1 LASTPIN (2775 600) BN 6
J 0
(2763 608);
DISPLAY 0.680851 (2763 608);
PAINT GREEN (2763 608);
FORCEPROP 2 LAST CDS_LIB standard
J 0
(2825 600);
PAINT MONO (2825 600);
DISPLAY INVISIBLE (2825 600);
FORCEPROP 1 LAST BODY_TYPE PLUMBING
J 0
(2825 650);
DISPLAY 0.872340 (2825 650);
PAINT GREEN (2825 650);
DISPLAY INVISIBLE (2825 650);
FORCEPROP 1 LAST HDL_TAP TRUE
J 0
(3150 475);
DISPLAY 0.872340 (3150 475);
DISPLAY INVISIBLE (3150 475);
FORCEPROP 1 LAST PATH I307
J 0
(2823 600);
DISPLAY 0.872340 (2823 600);
PAINT GREEN (2823 600);
DISPLAY INVISIBLE (2823 600);
FORCEADD TAP..1
(2825 650);
FORCEPROP 3 LASTPIN (2775 650) SIG_NAME P5E_CPU0_PE3_TX_DP<7>
J 0
(2785 660);
DISPLAY 0.659574 (2785 660);
PAINT MONO (2785 660);
DISPLAY INVISIBLE (2785 660);
FORCEPROP 1 LASTPIN (2775 650) BN 7
J 0
(2763 658);
DISPLAY 0.680851 (2763 658);
PAINT GREEN (2763 658);
FORCEPROP 2 LAST CDS_LIB standard
J 0
(2825 650);
PAINT MONO (2825 650);
DISPLAY INVISIBLE (2825 650);
FORCEPROP 1 LAST BODY_TYPE PLUMBING
J 0
(2825 700);
DISPLAY 0.872340 (2825 700);
PAINT GREEN (2825 700);
DISPLAY INVISIBLE (2825 700);
FORCEPROP 1 LAST HDL_TAP TRUE
J 0
(3150 525);
DISPLAY 0.872340 (3150 525);
DISPLAY INVISIBLE (3150 525);
FORCEPROP 1 LAST PATH I308
J 0
(2823 650);
DISPLAY 0.872340 (2823 650);
PAINT GREEN (2823 650);
DISPLAY INVISIBLE (2823 650);
FORCEADD TAP..1
(2825 750);
FORCEPROP 3 LASTPIN (2775 750) SIG_NAME P5E_CPU0_PE3_TX_DP<9>
J 0
(2785 760);
DISPLAY 0.659574 (2785 760);
PAINT MONO (2785 760);
DISPLAY INVISIBLE (2785 760);
FORCEPROP 1 LASTPIN (2775 750) BN 9
J 0
(2763 758);
DISPLAY 0.680851 (2763 758);
PAINT GREEN (2763 758);
FORCEPROP 2 LAST CDS_LIB standard
J 0
(2825 750);
DISPLAY INVISIBLE (2825 750);
FORCEPROP 1 LAST BODY_TYPE PLUMBING
J 0
(2825 800);
DISPLAY 0.872340 (2825 800);
PAINT GREEN (2825 800);
DISPLAY INVISIBLE (2825 800);
FORCEPROP 1 LAST HDL_TAP TRUE
J 0
(3150 625);
DISPLAY 0.872340 (3150 625);
DISPLAY INVISIBLE (3150 625);
FORCEPROP 1 LAST PATH I309
J 0
(2823 750);
DISPLAY 0.872340 (2823 750);
PAINT GREEN (2823 750);
DISPLAY INVISIBLE (2823 750);
FORCEADD TAP..1
(2825 700);
FORCEPROP 3 LASTPIN (2775 700) SIG_NAME P5E_CPU0_PE3_TX_DP<8>
J 0
(2785 710);
DISPLAY 0.659574 (2785 710);
PAINT MONO (2785 710);
DISPLAY INVISIBLE (2785 710);
FORCEPROP 1 LASTPIN (2775 700) BN 8
J 0
(2763 708);
DISPLAY 0.680851 (2763 708);
PAINT GREEN (2763 708);
FORCEPROP 2 LAST CDS_LIB standard
J 0
(2825 700);
PAINT MONO (2825 700);
DISPLAY INVISIBLE (2825 700);
FORCEPROP 1 LAST BODY_TYPE PLUMBING
J 0
(2825 750);
DISPLAY 0.872340 (2825 750);
PAINT GREEN (2825 750);
DISPLAY INVISIBLE (2825 750);
FORCEPROP 1 LAST HDL_TAP TRUE
J 0
(3150 575);
DISPLAY 0.872340 (3150 575);
DISPLAY INVISIBLE (3150 575);
FORCEPROP 1 LAST PATH I310
J 0
(2823 700);
DISPLAY 0.872340 (2823 700);
PAINT GREEN (2823 700);
DISPLAY INVISIBLE (2823 700);
FORCEADD TAP..1
(2825 800);
FORCEPROP 3 LASTPIN (2775 800) SIG_NAME P5E_CPU0_PE3_TX_DP<10>
J 0
(2785 810);
DISPLAY 0.659574 (2785 810);
PAINT MONO (2785 810);
DISPLAY INVISIBLE (2785 810);
FORCEPROP 1 LASTPIN (2775 800) BN 10
J 0
(2763 808);
DISPLAY 0.680851 (2763 808);
PAINT GREEN (2763 808);
FORCEPROP 2 LAST CDS_LIB standard
J 0
(2825 800);
DISPLAY INVISIBLE (2825 800);
FORCEPROP 1 LAST BODY_TYPE PLUMBING
J 0
(2825 850);
DISPLAY 0.872340 (2825 850);
PAINT GREEN (2825 850);
DISPLAY INVISIBLE (2825 850);
FORCEPROP 1 LAST HDL_TAP TRUE
J 0
(3150 675);
DISPLAY 0.872340 (3150 675);
DISPLAY INVISIBLE (3150 675);
FORCEPROP 1 LAST PATH I311
J 0
(2823 800);
DISPLAY 0.872340 (2823 800);
PAINT GREEN (2823 800);
DISPLAY INVISIBLE (2823 800);
FORCEADD TAP..1
(2825 900);
FORCEPROP 3 LASTPIN (2775 900) SIG_NAME P5E_CPU0_PE3_TX_DP<12>
J 0
(2785 910);
DISPLAY 0.659574 (2785 910);
PAINT MONO (2785 910);
DISPLAY INVISIBLE (2785 910);
FORCEPROP 1 LASTPIN (2775 900) BN 12
J 0
(2763 908);
DISPLAY 0.680851 (2763 908);
PAINT GREEN (2763 908);
FORCEPROP 2 LAST CDS_LIB standard
J 0
(2825 900);
DISPLAY INVISIBLE (2825 900);
FORCEPROP 1 LAST BODY_TYPE PLUMBING
J 0
(2825 950);
DISPLAY 0.872340 (2825 950);
PAINT GREEN (2825 950);
DISPLAY INVISIBLE (2825 950);
FORCEPROP 1 LAST HDL_TAP TRUE
J 0
(3150 775);
DISPLAY 0.872340 (3150 775);
DISPLAY INVISIBLE (3150 775);
FORCEPROP 1 LAST PATH I312
J 0
(2823 900);
DISPLAY 0.872340 (2823 900);
PAINT GREEN (2823 900);
DISPLAY INVISIBLE (2823 900);
FORCEADD TAP..1
(2825 850);
FORCEPROP 3 LASTPIN (2775 850) SIG_NAME P5E_CPU0_PE3_TX_DP<11>
J 0
(2785 860);
DISPLAY 0.659574 (2785 860);
PAINT MONO (2785 860);
DISPLAY INVISIBLE (2785 860);
FORCEPROP 1 LASTPIN (2775 850) BN 11
J 0
(2763 858);
DISPLAY 0.680851 (2763 858);
PAINT GREEN (2763 858);
FORCEPROP 2 LAST CDS_LIB standard
J 0
(2825 850);
DISPLAY INVISIBLE (2825 850);
FORCEPROP 1 LAST BODY_TYPE PLUMBING
J 0
(2825 900);
DISPLAY 0.872340 (2825 900);
PAINT GREEN (2825 900);
DISPLAY INVISIBLE (2825 900);
FORCEPROP 1 LAST HDL_TAP TRUE
J 0
(3150 725);
DISPLAY 0.872340 (3150 725);
DISPLAY INVISIBLE (3150 725);
FORCEPROP 1 LAST PATH I313
J 0
(2823 850);
DISPLAY 0.872340 (2823 850);
PAINT GREEN (2823 850);
DISPLAY INVISIBLE (2823 850);
FORCEADD TAP..1
(2825 1000);
FORCEPROP 3 LASTPIN (2775 1000) SIG_NAME P5E_CPU0_PE3_TX_DP<14>
J 0
(2785 1010);
DISPLAY 0.659574 (2785 1010);
PAINT MONO (2785 1010);
DISPLAY INVISIBLE (2785 1010);
FORCEPROP 1 LASTPIN (2775 1000) BN 14
J 0
(2763 1008);
DISPLAY 0.680851 (2763 1008);
PAINT GREEN (2763 1008);
FORCEPROP 2 LAST CDS_LIB standard
J 0
(2825 1000);
DISPLAY INVISIBLE (2825 1000);
FORCEPROP 1 LAST BODY_TYPE PLUMBING
J 0
(2825 1050);
DISPLAY 0.872340 (2825 1050);
PAINT GREEN (2825 1050);
DISPLAY INVISIBLE (2825 1050);
FORCEPROP 1 LAST HDL_TAP TRUE
J 0
(3150 875);
DISPLAY 0.872340 (3150 875);
DISPLAY INVISIBLE (3150 875);
FORCEPROP 1 LAST PATH I314
J 0
(2823 1000);
DISPLAY 0.872340 (2823 1000);
PAINT GREEN (2823 1000);
DISPLAY INVISIBLE (2823 1000);
FORCEADD TAP..1
(2825 950);
FORCEPROP 3 LASTPIN (2775 950) SIG_NAME P5E_CPU0_PE3_TX_DP<13>
J 0
(2785 960);
DISPLAY 0.659574 (2785 960);
PAINT MONO (2785 960);
DISPLAY INVISIBLE (2785 960);
FORCEPROP 1 LASTPIN (2775 950) BN 13
J 0
(2763 958);
DISPLAY 0.680851 (2763 958);
PAINT GREEN (2763 958);
FORCEPROP 2 LAST CDS_LIB standard
J 0
(2825 950);
DISPLAY INVISIBLE (2825 950);
FORCEPROP 1 LAST BODY_TYPE PLUMBING
J 0
(2825 1000);
DISPLAY 0.872340 (2825 1000);
PAINT GREEN (2825 1000);
DISPLAY INVISIBLE (2825 1000);
FORCEPROP 1 LAST HDL_TAP TRUE
J 0
(3150 825);
DISPLAY 0.872340 (3150 825);
DISPLAY INVISIBLE (3150 825);
FORCEPROP 1 LAST PATH I315
J 0
(2823 950);
DISPLAY 0.872340 (2823 950);
PAINT GREEN (2823 950);
DISPLAY INVISIBLE (2823 950);
FORCEADD TAP..1
(2825 1050);
FORCEPROP 3 LASTPIN (2775 1050) SIG_NAME P5E_CPU0_PE3_TX_DP<15>
J 0
(2785 1060);
DISPLAY 0.659574 (2785 1060);
PAINT MONO (2785 1060);
DISPLAY INVISIBLE (2785 1060);
FORCEPROP 1 LASTPIN (2775 1050) BN 15
J 0
(2763 1058);
DISPLAY 0.680851 (2763 1058);
PAINT GREEN (2763 1058);
FORCEPROP 2 LAST CDS_LIB standard
J 0
(2825 1050);
DISPLAY INVISIBLE (2825 1050);
FORCEPROP 1 LAST BODY_TYPE PLUMBING
J 0
(2825 1100);
DISPLAY 0.872340 (2825 1100);
PAINT GREEN (2825 1100);
DISPLAY INVISIBLE (2825 1100);
FORCEPROP 1 LAST HDL_TAP TRUE
J 0
(3150 925);
DISPLAY 0.872340 (3150 925);
DISPLAY INVISIBLE (3150 925);
FORCEPROP 1 LAST PATH I316
J 0
(2823 1050);
DISPLAY 0.872340 (2823 1050);
PAINT GREEN (2823 1050);
DISPLAY INVISIBLE (2823 1050);
FORCEADD OFFPAGE..2
(3925 225);
FORCEPROP 2 LAST $XR0 174 
J 0
(4114 225);
DISPLAY 0.638298 (4114 225);
PAINT MONO (4114 225);
FORCEPROP 2 LAST CDS_LIB standard
J 0
(3925 225);
PAINT MONO (3925 225);
DISPLAY INVISIBLE (3925 225);
FORCEPROP 1 LAST OFFPAGE TRUE
J 0
(4250 100);
DISPLAY 1.170213 (4250 100);
PAINT GREEN (4250 100);
DISPLAY INVISIBLE (4250 100);
FORCEPROP 1 LAST COMMENT_BODY TRUE
J 0
(3880 130);
DISPLAY 1.170213 (3880 130);
PAINT GREEN (3880 130);
DISPLAY INVISIBLE (3880 130);
FORCEPROP 2 LAST PATH I317
J 0
(4125 275);
DISPLAY 1.021277 (4125 275);
DISPLAY INVISIBLE (4125 275);
FORCEADD OFFPAGE..2
(3925 1075);
FORCEPROP 2 LAST $XR0 174 
J 0
(4114 1075);
DISPLAY 0.638298 (4114 1075);
PAINT MONO (4114 1075);
FORCEPROP 2 LAST CDS_LIB standard
J 0
(3925 1075);
PAINT MONO (3925 1075);
DISPLAY INVISIBLE (3925 1075);
FORCEPROP 1 LAST OFFPAGE TRUE
J 0
(4250 950);
DISPLAY 1.170213 (4250 950);
PAINT GREEN (4250 950);
DISPLAY INVISIBLE (4250 950);
FORCEPROP 1 LAST COMMENT_BODY TRUE
J 0
(3880 980);
DISPLAY 1.170213 (3880 980);
PAINT GREEN (3880 980);
DISPLAY INVISIBLE (3880 980);
FORCEPROP 2 LAST PATH I318
J 0
(4125 1125);
DISPLAY 1.021277 (4125 1125);
DISPLAY INVISIBLE (4125 1125);
FORCEADD TAP..1
(2825 2225);
FORCEPROP 3 LASTPIN (2775 2225) SIG_NAME P5E_CPU0_PE2_TX_DN<0>
J 0
(2785 2235);
DISPLAY 0.659574 (2785 2235);
PAINT MONO (2785 2235);
DISPLAY INVISIBLE (2785 2235);
FORCEPROP 1 LASTPIN (2775 2225) BN 0
J 0
(2763 2233);
DISPLAY 0.680851 (2763 2233);
PAINT GREEN (2763 2233);
FORCEPROP 2 LAST CDS_LIB standard
J 0
(2825 2225);
PAINT MONO (2825 2225);
DISPLAY INVISIBLE (2825 2225);
FORCEPROP 1 LAST BODY_TYPE PLUMBING
J 0
(2825 2275);
DISPLAY 0.872340 (2825 2275);
PAINT GREEN (2825 2275);
DISPLAY INVISIBLE (2825 2275);
FORCEPROP 1 LAST HDL_TAP TRUE
J 0
(3150 2100);
DISPLAY 0.872340 (3150 2100);
DISPLAY INVISIBLE (3150 2100);
FORCEPROP 1 LAST PATH I319
J 0
(2823 2225);
DISPLAY 0.872340 (2823 2225);
PAINT GREEN (2823 2225);
DISPLAY INVISIBLE (2823 2225);
FORCEADD TAP..1
(2825 2275);
FORCEPROP 3 LASTPIN (2775 2275) SIG_NAME P5E_CPU0_PE2_TX_DN<1>
J 0
(2785 2285);
DISPLAY 0.659574 (2785 2285);
PAINT MONO (2785 2285);
DISPLAY INVISIBLE (2785 2285);
FORCEPROP 1 LASTPIN (2775 2275) BN 1
J 0
(2763 2283);
DISPLAY 0.680851 (2763 2283);
PAINT GREEN (2763 2283);
FORCEPROP 2 LAST CDS_LIB standard
J 0
(2825 2275);
PAINT MONO (2825 2275);
DISPLAY INVISIBLE (2825 2275);
FORCEPROP 1 LAST BODY_TYPE PLUMBING
J 0
(2825 2325);
DISPLAY 0.872340 (2825 2325);
PAINT GREEN (2825 2325);
DISPLAY INVISIBLE (2825 2325);
FORCEPROP 1 LAST HDL_TAP TRUE
J 0
(3150 2150);
DISPLAY 0.872340 (3150 2150);
DISPLAY INVISIBLE (3150 2150);
FORCEPROP 1 LAST PATH I320
J 0
(2823 2275);
DISPLAY 0.872340 (2823 2275);
PAINT GREEN (2823 2275);
DISPLAY INVISIBLE (2823 2275);
FORCEADD TAP..1
(2825 2375);
FORCEPROP 3 LASTPIN (2775 2375) SIG_NAME P5E_CPU0_PE2_TX_DN<3>
J 0
(2785 2385);
DISPLAY 0.659574 (2785 2385);
PAINT MONO (2785 2385);
DISPLAY INVISIBLE (2785 2385);
FORCEPROP 1 LASTPIN (2775 2375) BN 3
J 0
(2763 2383);
DISPLAY 0.680851 (2763 2383);
PAINT GREEN (2763 2383);
FORCEPROP 2 LAST CDS_LIB standard
J 0
(2825 2375);
PAINT MONO (2825 2375);
DISPLAY INVISIBLE (2825 2375);
FORCEPROP 1 LAST BODY_TYPE PLUMBING
J 0
(2825 2425);
DISPLAY 0.872340 (2825 2425);
PAINT GREEN (2825 2425);
DISPLAY INVISIBLE (2825 2425);
FORCEPROP 1 LAST HDL_TAP TRUE
J 0
(3150 2250);
DISPLAY 0.872340 (3150 2250);
DISPLAY INVISIBLE (3150 2250);
FORCEPROP 1 LAST PATH I321
J 0
(2823 2375);
DISPLAY 0.872340 (2823 2375);
PAINT GREEN (2823 2375);
DISPLAY INVISIBLE (2823 2375);
FORCEADD TAP..1
(2825 2325);
FORCEPROP 3 LASTPIN (2775 2325) SIG_NAME P5E_CPU0_PE2_TX_DN<2>
J 0
(2785 2335);
DISPLAY 0.659574 (2785 2335);
PAINT MONO (2785 2335);
DISPLAY INVISIBLE (2785 2335);
FORCEPROP 1 LASTPIN (2775 2325) BN 2
J 0
(2763 2333);
DISPLAY 0.680851 (2763 2333);
PAINT GREEN (2763 2333);
FORCEPROP 2 LAST CDS_LIB standard
J 0
(2825 2325);
PAINT MONO (2825 2325);
DISPLAY INVISIBLE (2825 2325);
FORCEPROP 1 LAST BODY_TYPE PLUMBING
J 0
(2825 2375);
DISPLAY 0.872340 (2825 2375);
PAINT GREEN (2825 2375);
DISPLAY INVISIBLE (2825 2375);
FORCEPROP 1 LAST HDL_TAP TRUE
J 0
(3150 2200);
DISPLAY 0.872340 (3150 2200);
DISPLAY INVISIBLE (3150 2200);
FORCEPROP 1 LAST PATH I322
J 0
(2823 2325);
DISPLAY 0.872340 (2823 2325);
PAINT GREEN (2823 2325);
DISPLAY INVISIBLE (2823 2325);
FORCEADD TAP..1
(2825 2425);
FORCEPROP 3 LASTPIN (2775 2425) SIG_NAME P5E_CPU0_PE2_TX_DN<4>
J 0
(2785 2435);
DISPLAY 0.659574 (2785 2435);
PAINT MONO (2785 2435);
DISPLAY INVISIBLE (2785 2435);
FORCEPROP 1 LASTPIN (2775 2425) BN 4
J 0
(2763 2433);
DISPLAY 0.680851 (2763 2433);
PAINT GREEN (2763 2433);
FORCEPROP 2 LAST CDS_LIB standard
J 0
(2825 2425);
PAINT MONO (2825 2425);
DISPLAY INVISIBLE (2825 2425);
FORCEPROP 1 LAST BODY_TYPE PLUMBING
J 0
(2825 2475);
DISPLAY 0.872340 (2825 2475);
PAINT GREEN (2825 2475);
DISPLAY INVISIBLE (2825 2475);
FORCEPROP 1 LAST HDL_TAP TRUE
J 0
(3150 2300);
DISPLAY 0.872340 (3150 2300);
DISPLAY INVISIBLE (3150 2300);
FORCEPROP 1 LAST PATH I323
J 0
(2823 2425);
DISPLAY 0.872340 (2823 2425);
PAINT GREEN (2823 2425);
DISPLAY INVISIBLE (2823 2425);
FORCEADD TAP..1
(2825 2525);
FORCEPROP 3 LASTPIN (2775 2525) SIG_NAME P5E_CPU0_PE2_TX_DN<6>
J 0
(2785 2535);
DISPLAY 0.659574 (2785 2535);
PAINT MONO (2785 2535);
DISPLAY INVISIBLE (2785 2535);
FORCEPROP 1 LASTPIN (2775 2525) BN 6
J 0
(2763 2533);
DISPLAY 0.680851 (2763 2533);
PAINT GREEN (2763 2533);
FORCEPROP 2 LAST CDS_LIB standard
J 0
(2825 2525);
PAINT MONO (2825 2525);
DISPLAY INVISIBLE (2825 2525);
FORCEPROP 1 LAST BODY_TYPE PLUMBING
J 0
(2825 2575);
DISPLAY 0.872340 (2825 2575);
PAINT GREEN (2825 2575);
DISPLAY INVISIBLE (2825 2575);
FORCEPROP 1 LAST HDL_TAP TRUE
J 0
(3150 2400);
DISPLAY 0.872340 (3150 2400);
DISPLAY INVISIBLE (3150 2400);
FORCEPROP 1 LAST PATH I324
J 0
(2823 2525);
DISPLAY 0.872340 (2823 2525);
PAINT GREEN (2823 2525);
DISPLAY INVISIBLE (2823 2525);
FORCEADD TAP..1
(2825 2475);
FORCEPROP 3 LASTPIN (2775 2475) SIG_NAME P5E_CPU0_PE2_TX_DN<5>
J 0
(2785 2485);
DISPLAY 0.659574 (2785 2485);
PAINT MONO (2785 2485);
DISPLAY INVISIBLE (2785 2485);
FORCEPROP 1 LASTPIN (2775 2475) BN 5
J 0
(2763 2483);
DISPLAY 0.680851 (2763 2483);
PAINT GREEN (2763 2483);
FORCEPROP 2 LAST CDS_LIB standard
J 0
(2825 2475);
PAINT MONO (2825 2475);
DISPLAY INVISIBLE (2825 2475);
FORCEPROP 1 LAST BODY_TYPE PLUMBING
J 0
(2825 2525);
DISPLAY 0.872340 (2825 2525);
PAINT GREEN (2825 2525);
DISPLAY INVISIBLE (2825 2525);
FORCEPROP 1 LAST HDL_TAP TRUE
J 0
(3150 2350);
DISPLAY 0.872340 (3150 2350);
DISPLAY INVISIBLE (3150 2350);
FORCEPROP 1 LAST PATH I325
J 0
(2823 2475);
DISPLAY 0.872340 (2823 2475);
PAINT GREEN (2823 2475);
DISPLAY INVISIBLE (2823 2475);
FORCEADD TAP..1
(2825 2625);
FORCEPROP 3 LASTPIN (2775 2625) SIG_NAME P5E_CPU0_PE2_TX_DN<8>
J 0
(2785 2635);
DISPLAY 0.659574 (2785 2635);
PAINT MONO (2785 2635);
DISPLAY INVISIBLE (2785 2635);
FORCEPROP 1 LASTPIN (2775 2625) BN 8
J 0
(2763 2633);
DISPLAY 0.680851 (2763 2633);
PAINT GREEN (2763 2633);
FORCEPROP 2 LAST CDS_LIB standard
J 0
(2825 2625);
PAINT MONO (2825 2625);
DISPLAY INVISIBLE (2825 2625);
FORCEPROP 1 LAST BODY_TYPE PLUMBING
J 0
(2825 2675);
DISPLAY 0.872340 (2825 2675);
PAINT GREEN (2825 2675);
DISPLAY INVISIBLE (2825 2675);
FORCEPROP 1 LAST HDL_TAP TRUE
J 0
(3150 2500);
DISPLAY 0.872340 (3150 2500);
DISPLAY INVISIBLE (3150 2500);
FORCEPROP 1 LAST PATH I326
J 0
(2823 2625);
DISPLAY 0.872340 (2823 2625);
PAINT GREEN (2823 2625);
DISPLAY INVISIBLE (2823 2625);
FORCEADD TAP..1
(2825 2575);
FORCEPROP 3 LASTPIN (2775 2575) SIG_NAME P5E_CPU0_PE2_TX_DN<7>
J 0
(2785 2585);
DISPLAY 0.659574 (2785 2585);
PAINT MONO (2785 2585);
DISPLAY INVISIBLE (2785 2585);
FORCEPROP 1 LASTPIN (2775 2575) BN 7
J 0
(2763 2583);
DISPLAY 0.680851 (2763 2583);
PAINT GREEN (2763 2583);
FORCEPROP 2 LAST CDS_LIB standard
J 0
(2825 2575);
PAINT MONO (2825 2575);
DISPLAY INVISIBLE (2825 2575);
FORCEPROP 1 LAST BODY_TYPE PLUMBING
J 0
(2825 2625);
DISPLAY 0.872340 (2825 2625);
PAINT GREEN (2825 2625);
DISPLAY INVISIBLE (2825 2625);
FORCEPROP 1 LAST HDL_TAP TRUE
J 0
(3150 2450);
DISPLAY 0.872340 (3150 2450);
DISPLAY INVISIBLE (3150 2450);
FORCEPROP 1 LAST PATH I327
J 0
(2823 2575);
DISPLAY 0.872340 (2823 2575);
PAINT GREEN (2823 2575);
DISPLAY INVISIBLE (2823 2575);
FORCEADD TAP..1
(2825 2675);
FORCEPROP 3 LASTPIN (2775 2675) SIG_NAME P5E_CPU0_PE2_TX_DN<9>
J 0
(2785 2685);
DISPLAY 0.659574 (2785 2685);
PAINT MONO (2785 2685);
DISPLAY INVISIBLE (2785 2685);
FORCEPROP 1 LASTPIN (2775 2675) BN 9
J 0
(2763 2683);
DISPLAY 0.680851 (2763 2683);
PAINT GREEN (2763 2683);
FORCEPROP 2 LAST CDS_LIB standard
J 0
(2825 2675);
DISPLAY INVISIBLE (2825 2675);
FORCEPROP 1 LAST BODY_TYPE PLUMBING
J 0
(2825 2725);
DISPLAY 0.872340 (2825 2725);
PAINT GREEN (2825 2725);
DISPLAY INVISIBLE (2825 2725);
FORCEPROP 1 LAST HDL_TAP TRUE
J 0
(3150 2550);
DISPLAY 0.872340 (3150 2550);
DISPLAY INVISIBLE (3150 2550);
FORCEPROP 1 LAST PATH I328
J 0
(2823 2675);
DISPLAY 0.872340 (2823 2675);
PAINT GREEN (2823 2675);
DISPLAY INVISIBLE (2823 2675);
FORCEADD TAP..1
(2825 2725);
FORCEPROP 3 LASTPIN (2775 2725) SIG_NAME P5E_CPU0_PE2_TX_DN<10>
J 0
(2785 2735);
DISPLAY 0.659574 (2785 2735);
PAINT MONO (2785 2735);
DISPLAY INVISIBLE (2785 2735);
FORCEPROP 1 LASTPIN (2775 2725) BN 10
J 0
(2763 2733);
DISPLAY 0.680851 (2763 2733);
PAINT GREEN (2763 2733);
FORCEPROP 2 LAST CDS_LIB standard
J 0
(2825 2725);
DISPLAY INVISIBLE (2825 2725);
FORCEPROP 1 LAST BODY_TYPE PLUMBING
J 0
(2825 2775);
DISPLAY 0.872340 (2825 2775);
PAINT GREEN (2825 2775);
DISPLAY INVISIBLE (2825 2775);
FORCEPROP 1 LAST HDL_TAP TRUE
J 0
(3150 2600);
DISPLAY 0.872340 (3150 2600);
DISPLAY INVISIBLE (3150 2600);
FORCEPROP 1 LAST PATH I329
J 0
(2823 2725);
DISPLAY 0.872340 (2823 2725);
PAINT GREEN (2823 2725);
DISPLAY INVISIBLE (2823 2725);
FORCEADD TAP..1
(2825 2775);
FORCEPROP 3 LASTPIN (2775 2775) SIG_NAME P5E_CPU0_PE2_TX_DN<11>
J 0
(2785 2785);
DISPLAY 0.659574 (2785 2785);
PAINT MONO (2785 2785);
DISPLAY INVISIBLE (2785 2785);
FORCEPROP 1 LASTPIN (2775 2775) BN 11
J 0
(2763 2783);
DISPLAY 0.680851 (2763 2783);
PAINT GREEN (2763 2783);
FORCEPROP 2 LAST CDS_LIB standard
J 0
(2825 2775);
DISPLAY INVISIBLE (2825 2775);
FORCEPROP 1 LAST BODY_TYPE PLUMBING
J 0
(2825 2825);
DISPLAY 0.872340 (2825 2825);
PAINT GREEN (2825 2825);
DISPLAY INVISIBLE (2825 2825);
FORCEPROP 1 LAST HDL_TAP TRUE
J 0
(3150 2650);
DISPLAY 0.872340 (3150 2650);
DISPLAY INVISIBLE (3150 2650);
FORCEPROP 1 LAST PATH I330
J 0
(2823 2775);
DISPLAY 0.872340 (2823 2775);
PAINT GREEN (2823 2775);
DISPLAY INVISIBLE (2823 2775);
FORCEADD TAP..1
(2825 2825);
FORCEPROP 3 LASTPIN (2775 2825) SIG_NAME P5E_CPU0_PE2_TX_DN<12>
J 0
(2785 2835);
DISPLAY 0.659574 (2785 2835);
PAINT MONO (2785 2835);
DISPLAY INVISIBLE (2785 2835);
FORCEPROP 1 LASTPIN (2775 2825) BN 12
J 0
(2763 2833);
DISPLAY 0.680851 (2763 2833);
PAINT GREEN (2763 2833);
FORCEPROP 2 LAST CDS_LIB standard
J 0
(2825 2825);
DISPLAY INVISIBLE (2825 2825);
FORCEPROP 1 LAST BODY_TYPE PLUMBING
J 0
(2825 2875);
DISPLAY 0.872340 (2825 2875);
PAINT GREEN (2825 2875);
DISPLAY INVISIBLE (2825 2875);
FORCEPROP 1 LAST HDL_TAP TRUE
J 0
(3150 2700);
DISPLAY 0.872340 (3150 2700);
DISPLAY INVISIBLE (3150 2700);
FORCEPROP 1 LAST PATH I331
J 0
(2823 2825);
DISPLAY 0.872340 (2823 2825);
PAINT GREEN (2823 2825);
DISPLAY INVISIBLE (2823 2825);
FORCEADD TAP..1
(2825 2875);
FORCEPROP 3 LASTPIN (2775 2875) SIG_NAME P5E_CPU0_PE2_TX_DN<13>
J 0
(2785 2885);
DISPLAY 0.659574 (2785 2885);
PAINT MONO (2785 2885);
DISPLAY INVISIBLE (2785 2885);
FORCEPROP 1 LASTPIN (2775 2875) BN 13
J 0
(2763 2883);
DISPLAY 0.680851 (2763 2883);
PAINT GREEN (2763 2883);
FORCEPROP 2 LAST CDS_LIB standard
J 0
(2825 2875);
DISPLAY INVISIBLE (2825 2875);
FORCEPROP 1 LAST BODY_TYPE PLUMBING
J 0
(2825 2925);
DISPLAY 0.872340 (2825 2925);
PAINT GREEN (2825 2925);
DISPLAY INVISIBLE (2825 2925);
FORCEPROP 1 LAST HDL_TAP TRUE
J 0
(3150 2750);
DISPLAY 0.872340 (3150 2750);
DISPLAY INVISIBLE (3150 2750);
FORCEPROP 1 LAST PATH I332
J 0
(2823 2875);
DISPLAY 0.872340 (2823 2875);
PAINT GREEN (2823 2875);
DISPLAY INVISIBLE (2823 2875);
FORCEADD TAP..1
(2825 2925);
FORCEPROP 3 LASTPIN (2775 2925) SIG_NAME P5E_CPU0_PE2_TX_DN<14>
J 0
(2785 2935);
DISPLAY 0.659574 (2785 2935);
PAINT MONO (2785 2935);
DISPLAY INVISIBLE (2785 2935);
FORCEPROP 1 LASTPIN (2775 2925) BN 14
J 0
(2763 2933);
DISPLAY 0.680851 (2763 2933);
PAINT GREEN (2763 2933);
FORCEPROP 2 LAST CDS_LIB standard
J 0
(2825 2925);
DISPLAY INVISIBLE (2825 2925);
FORCEPROP 1 LAST BODY_TYPE PLUMBING
J 0
(2825 2975);
DISPLAY 0.872340 (2825 2975);
PAINT GREEN (2825 2975);
DISPLAY INVISIBLE (2825 2975);
FORCEPROP 1 LAST HDL_TAP TRUE
J 0
(3150 2800);
DISPLAY 0.872340 (3150 2800);
DISPLAY INVISIBLE (3150 2800);
FORCEPROP 1 LAST PATH I333
J 0
(2823 2925);
DISPLAY 0.872340 (2823 2925);
PAINT GREEN (2823 2925);
DISPLAY INVISIBLE (2823 2925);
FORCEADD TAP..1
(2825 2975);
FORCEPROP 3 LASTPIN (2775 2975) SIG_NAME P5E_CPU0_PE2_TX_DN<15>
J 0
(2785 2985);
DISPLAY 0.659574 (2785 2985);
PAINT MONO (2785 2985);
DISPLAY INVISIBLE (2785 2985);
FORCEPROP 1 LASTPIN (2775 2975) BN 15
J 0
(2763 2983);
DISPLAY 0.680851 (2763 2983);
PAINT GREEN (2763 2983);
FORCEPROP 2 LAST CDS_LIB standard
J 0
(2825 2975);
DISPLAY INVISIBLE (2825 2975);
FORCEPROP 1 LAST BODY_TYPE PLUMBING
J 0
(2825 3025);
DISPLAY 0.872340 (2825 3025);
PAINT GREEN (2825 3025);
DISPLAY INVISIBLE (2825 3025);
FORCEPROP 1 LAST HDL_TAP TRUE
J 0
(3150 2850);
DISPLAY 0.872340 (3150 2850);
DISPLAY INVISIBLE (3150 2850);
FORCEPROP 1 LAST PATH I334
J 0
(2823 2975);
DISPLAY 0.872340 (2823 2975);
PAINT GREEN (2823 2975);
DISPLAY INVISIBLE (2823 2975);
FORCEADD TAP..1
(2825 3075);
FORCEPROP 3 LASTPIN (2775 3075) SIG_NAME P5E_CPU0_PE2_TX_DP<0>
J 0
(2785 3085);
DISPLAY 0.659574 (2785 3085);
PAINT MONO (2785 3085);
DISPLAY INVISIBLE (2785 3085);
FORCEPROP 1 LASTPIN (2775 3075) BN 0
J 0
(2763 3083);
DISPLAY 0.680851 (2763 3083);
PAINT GREEN (2763 3083);
FORCEPROP 2 LAST CDS_LIB standard
J 0
(2825 3075);
PAINT MONO (2825 3075);
DISPLAY INVISIBLE (2825 3075);
FORCEPROP 1 LAST BODY_TYPE PLUMBING
J 0
(2825 3125);
DISPLAY 0.872340 (2825 3125);
PAINT GREEN (2825 3125);
DISPLAY INVISIBLE (2825 3125);
FORCEPROP 1 LAST HDL_TAP TRUE
J 0
(3150 2950);
DISPLAY 0.872340 (3150 2950);
DISPLAY INVISIBLE (3150 2950);
FORCEPROP 1 LAST PATH I335
J 0
(2823 3075);
DISPLAY 0.872340 (2823 3075);
PAINT GREEN (2823 3075);
DISPLAY INVISIBLE (2823 3075);
FORCEADD TAP..1
(2825 3125);
FORCEPROP 3 LASTPIN (2775 3125) SIG_NAME P5E_CPU0_PE2_TX_DP<1>
J 0
(2785 3135);
DISPLAY 0.659574 (2785 3135);
PAINT MONO (2785 3135);
DISPLAY INVISIBLE (2785 3135);
FORCEPROP 1 LASTPIN (2775 3125) BN 1
J 0
(2763 3133);
DISPLAY 0.680851 (2763 3133);
PAINT GREEN (2763 3133);
FORCEPROP 2 LAST CDS_LIB standard
J 0
(2825 3125);
PAINT MONO (2825 3125);
DISPLAY INVISIBLE (2825 3125);
FORCEPROP 1 LAST BODY_TYPE PLUMBING
J 0
(2825 3175);
DISPLAY 0.872340 (2825 3175);
PAINT GREEN (2825 3175);
DISPLAY INVISIBLE (2825 3175);
FORCEPROP 1 LAST HDL_TAP TRUE
J 0
(3150 3000);
DISPLAY 0.872340 (3150 3000);
DISPLAY INVISIBLE (3150 3000);
FORCEPROP 1 LAST PATH I336
J 0
(2823 3125);
DISPLAY 0.872340 (2823 3125);
PAINT GREEN (2823 3125);
DISPLAY INVISIBLE (2823 3125);
FORCEADD TAP..1
(2825 3175);
FORCEPROP 3 LASTPIN (2775 3175) SIG_NAME P5E_CPU0_PE2_TX_DP<2>
J 0
(2785 3185);
DISPLAY 0.659574 (2785 3185);
PAINT MONO (2785 3185);
DISPLAY INVISIBLE (2785 3185);
FORCEPROP 1 LASTPIN (2775 3175) BN 2
J 0
(2763 3183);
DISPLAY 0.680851 (2763 3183);
PAINT GREEN (2763 3183);
FORCEPROP 2 LAST CDS_LIB standard
J 0
(2825 3175);
PAINT MONO (2825 3175);
DISPLAY INVISIBLE (2825 3175);
FORCEPROP 1 LAST BODY_TYPE PLUMBING
J 0
(2825 3225);
DISPLAY 0.872340 (2825 3225);
PAINT GREEN (2825 3225);
DISPLAY INVISIBLE (2825 3225);
FORCEPROP 1 LAST HDL_TAP TRUE
J 0
(3150 3050);
DISPLAY 0.872340 (3150 3050);
DISPLAY INVISIBLE (3150 3050);
FORCEPROP 1 LAST PATH I337
J 0
(2823 3175);
DISPLAY 0.872340 (2823 3175);
PAINT GREEN (2823 3175);
DISPLAY INVISIBLE (2823 3175);
FORCEADD TAP..1
(2825 3275);
FORCEPROP 3 LASTPIN (2775 3275) SIG_NAME P5E_CPU0_PE2_TX_DP<4>
J 0
(2785 3285);
DISPLAY 0.659574 (2785 3285);
PAINT MONO (2785 3285);
DISPLAY INVISIBLE (2785 3285);
FORCEPROP 1 LASTPIN (2775 3275) BN 4
J 0
(2763 3283);
DISPLAY 0.680851 (2763 3283);
PAINT GREEN (2763 3283);
FORCEPROP 2 LAST CDS_LIB standard
J 0
(2825 3275);
PAINT MONO (2825 3275);
DISPLAY INVISIBLE (2825 3275);
FORCEPROP 1 LAST BODY_TYPE PLUMBING
J 0
(2825 3325);
DISPLAY 0.872340 (2825 3325);
PAINT GREEN (2825 3325);
DISPLAY INVISIBLE (2825 3325);
FORCEPROP 1 LAST HDL_TAP TRUE
J 0
(3150 3150);
DISPLAY 0.872340 (3150 3150);
DISPLAY INVISIBLE (3150 3150);
FORCEPROP 1 LAST PATH I338
J 0
(2823 3275);
DISPLAY 0.872340 (2823 3275);
PAINT GREEN (2823 3275);
DISPLAY INVISIBLE (2823 3275);
FORCEADD TAP..1
(2825 3225);
FORCEPROP 3 LASTPIN (2775 3225) SIG_NAME P5E_CPU0_PE2_TX_DP<3>
J 0
(2785 3235);
DISPLAY 0.659574 (2785 3235);
PAINT MONO (2785 3235);
DISPLAY INVISIBLE (2785 3235);
FORCEPROP 1 LASTPIN (2775 3225) BN 3
J 0
(2763 3233);
DISPLAY 0.680851 (2763 3233);
PAINT GREEN (2763 3233);
FORCEPROP 2 LAST CDS_LIB standard
J 0
(2825 3225);
PAINT MONO (2825 3225);
DISPLAY INVISIBLE (2825 3225);
FORCEPROP 1 LAST BODY_TYPE PLUMBING
J 0
(2825 3275);
DISPLAY 0.872340 (2825 3275);
PAINT GREEN (2825 3275);
DISPLAY INVISIBLE (2825 3275);
FORCEPROP 1 LAST HDL_TAP TRUE
J 0
(3150 3100);
DISPLAY 0.872340 (3150 3100);
DISPLAY INVISIBLE (3150 3100);
FORCEPROP 1 LAST PATH I339
J 0
(2823 3225);
DISPLAY 0.872340 (2823 3225);
PAINT GREEN (2823 3225);
DISPLAY INVISIBLE (2823 3225);
FORCEADD TAP..1
(2825 3325);
FORCEPROP 3 LASTPIN (2775 3325) SIG_NAME P5E_CPU0_PE2_TX_DP<5>
J 0
(2785 3335);
DISPLAY 0.659574 (2785 3335);
PAINT MONO (2785 3335);
DISPLAY INVISIBLE (2785 3335);
FORCEPROP 1 LASTPIN (2775 3325) BN 5
J 0
(2763 3333);
DISPLAY 0.680851 (2763 3333);
PAINT GREEN (2763 3333);
FORCEPROP 2 LAST CDS_LIB standard
J 0
(2825 3325);
PAINT MONO (2825 3325);
DISPLAY INVISIBLE (2825 3325);
FORCEPROP 1 LAST BODY_TYPE PLUMBING
J 0
(2825 3375);
DISPLAY 0.872340 (2825 3375);
PAINT GREEN (2825 3375);
DISPLAY INVISIBLE (2825 3375);
FORCEPROP 1 LAST HDL_TAP TRUE
J 0
(3150 3200);
DISPLAY 0.872340 (3150 3200);
DISPLAY INVISIBLE (3150 3200);
FORCEPROP 1 LAST PATH I340
J 0
(2823 3325);
DISPLAY 0.872340 (2823 3325);
PAINT GREEN (2823 3325);
DISPLAY INVISIBLE (2823 3325);
FORCEADD TAP..1
(2825 3375);
FORCEPROP 3 LASTPIN (2775 3375) SIG_NAME P5E_CPU0_PE2_TX_DP<6>
J 0
(2785 3385);
DISPLAY 0.659574 (2785 3385);
PAINT MONO (2785 3385);
DISPLAY INVISIBLE (2785 3385);
FORCEPROP 1 LASTPIN (2775 3375) BN 6
J 0
(2763 3383);
DISPLAY 0.680851 (2763 3383);
PAINT GREEN (2763 3383);
FORCEPROP 2 LAST CDS_LIB standard
J 0
(2825 3375);
PAINT MONO (2825 3375);
DISPLAY INVISIBLE (2825 3375);
FORCEPROP 1 LAST BODY_TYPE PLUMBING
J 0
(2825 3425);
DISPLAY 0.872340 (2825 3425);
PAINT GREEN (2825 3425);
DISPLAY INVISIBLE (2825 3425);
FORCEPROP 1 LAST HDL_TAP TRUE
J 0
(3150 3250);
DISPLAY 0.872340 (3150 3250);
DISPLAY INVISIBLE (3150 3250);
FORCEPROP 1 LAST PATH I341
J 0
(2823 3375);
DISPLAY 0.872340 (2823 3375);
PAINT GREEN (2823 3375);
DISPLAY INVISIBLE (2823 3375);
FORCEADD TAP..1
(2825 3425);
FORCEPROP 3 LASTPIN (2775 3425) SIG_NAME P5E_CPU0_PE2_TX_DP<7>
J 0
(2785 3435);
DISPLAY 0.659574 (2785 3435);
PAINT MONO (2785 3435);
DISPLAY INVISIBLE (2785 3435);
FORCEPROP 1 LASTPIN (2775 3425) BN 7
J 0
(2763 3433);
DISPLAY 0.680851 (2763 3433);
PAINT GREEN (2763 3433);
FORCEPROP 2 LAST CDS_LIB standard
J 0
(2825 3425);
PAINT MONO (2825 3425);
DISPLAY INVISIBLE (2825 3425);
FORCEPROP 1 LAST BODY_TYPE PLUMBING
J 0
(2825 3475);
DISPLAY 0.872340 (2825 3475);
PAINT GREEN (2825 3475);
DISPLAY INVISIBLE (2825 3475);
FORCEPROP 1 LAST HDL_TAP TRUE
J 0
(3150 3300);
DISPLAY 0.872340 (3150 3300);
DISPLAY INVISIBLE (3150 3300);
FORCEPROP 1 LAST PATH I342
J 0
(2823 3425);
DISPLAY 0.872340 (2823 3425);
PAINT GREEN (2823 3425);
DISPLAY INVISIBLE (2823 3425);
FORCEADD TAP..1
(2825 3525);
FORCEPROP 3 LASTPIN (2775 3525) SIG_NAME P5E_CPU0_PE2_TX_DP<9>
J 0
(2785 3535);
DISPLAY 0.659574 (2785 3535);
PAINT MONO (2785 3535);
DISPLAY INVISIBLE (2785 3535);
FORCEPROP 1 LASTPIN (2775 3525) BN 9
J 0
(2763 3533);
DISPLAY 0.680851 (2763 3533);
PAINT GREEN (2763 3533);
FORCEPROP 2 LAST CDS_LIB standard
J 0
(2825 3525);
DISPLAY INVISIBLE (2825 3525);
FORCEPROP 1 LAST BODY_TYPE PLUMBING
J 0
(2825 3575);
DISPLAY 0.872340 (2825 3575);
PAINT GREEN (2825 3575);
DISPLAY INVISIBLE (2825 3575);
FORCEPROP 1 LAST HDL_TAP TRUE
J 0
(3150 3400);
DISPLAY 0.872340 (3150 3400);
DISPLAY INVISIBLE (3150 3400);
FORCEPROP 1 LAST PATH I343
J 0
(2823 3525);
DISPLAY 0.872340 (2823 3525);
PAINT GREEN (2823 3525);
DISPLAY INVISIBLE (2823 3525);
FORCEADD TAP..1
(2825 3475);
FORCEPROP 3 LASTPIN (2775 3475) SIG_NAME P5E_CPU0_PE2_TX_DP<8>
J 0
(2785 3485);
DISPLAY 0.659574 (2785 3485);
PAINT MONO (2785 3485);
DISPLAY INVISIBLE (2785 3485);
FORCEPROP 1 LASTPIN (2775 3475) BN 8
J 0
(2763 3483);
DISPLAY 0.680851 (2763 3483);
PAINT GREEN (2763 3483);
FORCEPROP 2 LAST CDS_LIB standard
J 0
(2825 3475);
PAINT MONO (2825 3475);
DISPLAY INVISIBLE (2825 3475);
FORCEPROP 1 LAST BODY_TYPE PLUMBING
J 0
(2825 3525);
DISPLAY 0.872340 (2825 3525);
PAINT GREEN (2825 3525);
DISPLAY INVISIBLE (2825 3525);
FORCEPROP 1 LAST HDL_TAP TRUE
J 0
(3150 3350);
DISPLAY 0.872340 (3150 3350);
DISPLAY INVISIBLE (3150 3350);
FORCEPROP 1 LAST PATH I344
J 0
(2823 3475);
DISPLAY 0.872340 (2823 3475);
PAINT GREEN (2823 3475);
DISPLAY INVISIBLE (2823 3475);
FORCEADD TAP..1
(2825 3575);
FORCEPROP 3 LASTPIN (2775 3575) SIG_NAME P5E_CPU0_PE2_TX_DP<10>
J 0
(2785 3585);
DISPLAY 0.659574 (2785 3585);
PAINT MONO (2785 3585);
DISPLAY INVISIBLE (2785 3585);
FORCEPROP 1 LASTPIN (2775 3575) BN 10
J 0
(2763 3583);
DISPLAY 0.680851 (2763 3583);
PAINT GREEN (2763 3583);
FORCEPROP 2 LAST CDS_LIB standard
J 0
(2825 3575);
DISPLAY INVISIBLE (2825 3575);
FORCEPROP 1 LAST BODY_TYPE PLUMBING
J 0
(2825 3625);
DISPLAY 0.872340 (2825 3625);
PAINT GREEN (2825 3625);
DISPLAY INVISIBLE (2825 3625);
FORCEPROP 1 LAST HDL_TAP TRUE
J 0
(3150 3450);
DISPLAY 0.872340 (3150 3450);
DISPLAY INVISIBLE (3150 3450);
FORCEPROP 1 LAST PATH I345
J 0
(2823 3575);
DISPLAY 0.872340 (2823 3575);
PAINT GREEN (2823 3575);
DISPLAY INVISIBLE (2823 3575);
FORCEADD TAP..1
(2825 3675);
FORCEPROP 3 LASTPIN (2775 3675) SIG_NAME P5E_CPU0_PE2_TX_DP<12>
J 0
(2785 3685);
DISPLAY 0.659574 (2785 3685);
PAINT MONO (2785 3685);
DISPLAY INVISIBLE (2785 3685);
FORCEPROP 1 LASTPIN (2775 3675) BN 12
J 0
(2763 3683);
DISPLAY 0.680851 (2763 3683);
PAINT GREEN (2763 3683);
FORCEPROP 2 LAST CDS_LIB standard
J 0
(2825 3675);
DISPLAY INVISIBLE (2825 3675);
FORCEPROP 1 LAST BODY_TYPE PLUMBING
J 0
(2825 3725);
DISPLAY 0.872340 (2825 3725);
PAINT GREEN (2825 3725);
DISPLAY INVISIBLE (2825 3725);
FORCEPROP 1 LAST HDL_TAP TRUE
J 0
(3150 3550);
DISPLAY 0.872340 (3150 3550);
DISPLAY INVISIBLE (3150 3550);
FORCEPROP 1 LAST PATH I346
J 0
(2823 3675);
DISPLAY 0.872340 (2823 3675);
PAINT GREEN (2823 3675);
DISPLAY INVISIBLE (2823 3675);
FORCEADD TAP..1
(2825 3625);
FORCEPROP 3 LASTPIN (2775 3625) SIG_NAME P5E_CPU0_PE2_TX_DP<11>
J 0
(2785 3635);
DISPLAY 0.659574 (2785 3635);
PAINT MONO (2785 3635);
DISPLAY INVISIBLE (2785 3635);
FORCEPROP 1 LASTPIN (2775 3625) BN 11
J 0
(2763 3633);
DISPLAY 0.680851 (2763 3633);
PAINT GREEN (2763 3633);
FORCEPROP 2 LAST CDS_LIB standard
J 0
(2825 3625);
DISPLAY INVISIBLE (2825 3625);
FORCEPROP 1 LAST BODY_TYPE PLUMBING
J 0
(2825 3675);
DISPLAY 0.872340 (2825 3675);
PAINT GREEN (2825 3675);
DISPLAY INVISIBLE (2825 3675);
FORCEPROP 1 LAST HDL_TAP TRUE
J 0
(3150 3500);
DISPLAY 0.872340 (3150 3500);
DISPLAY INVISIBLE (3150 3500);
FORCEPROP 1 LAST PATH I347
J 0
(2823 3625);
DISPLAY 0.872340 (2823 3625);
PAINT GREEN (2823 3625);
DISPLAY INVISIBLE (2823 3625);
FORCEADD TAP..1
(2825 3775);
FORCEPROP 3 LASTPIN (2775 3775) SIG_NAME P5E_CPU0_PE2_TX_DP<14>
J 0
(2785 3785);
DISPLAY 0.659574 (2785 3785);
PAINT MONO (2785 3785);
DISPLAY INVISIBLE (2785 3785);
FORCEPROP 1 LASTPIN (2775 3775) BN 14
J 0
(2763 3783);
DISPLAY 0.680851 (2763 3783);
PAINT GREEN (2763 3783);
FORCEPROP 2 LAST CDS_LIB standard
J 0
(2825 3775);
DISPLAY INVISIBLE (2825 3775);
FORCEPROP 1 LAST BODY_TYPE PLUMBING
J 0
(2825 3825);
DISPLAY 0.872340 (2825 3825);
PAINT GREEN (2825 3825);
DISPLAY INVISIBLE (2825 3825);
FORCEPROP 1 LAST HDL_TAP TRUE
J 0
(3150 3650);
DISPLAY 0.872340 (3150 3650);
DISPLAY INVISIBLE (3150 3650);
FORCEPROP 1 LAST PATH I348
J 0
(2823 3775);
DISPLAY 0.872340 (2823 3775);
PAINT GREEN (2823 3775);
DISPLAY INVISIBLE (2823 3775);
FORCEADD TAP..1
(2825 3725);
FORCEPROP 3 LASTPIN (2775 3725) SIG_NAME P5E_CPU0_PE2_TX_DP<13>
J 0
(2785 3735);
DISPLAY 0.659574 (2785 3735);
PAINT MONO (2785 3735);
DISPLAY INVISIBLE (2785 3735);
FORCEPROP 1 LASTPIN (2775 3725) BN 13
J 0
(2763 3733);
DISPLAY 0.680851 (2763 3733);
PAINT GREEN (2763 3733);
FORCEPROP 2 LAST CDS_LIB standard
J 0
(2825 3725);
DISPLAY INVISIBLE (2825 3725);
FORCEPROP 1 LAST BODY_TYPE PLUMBING
J 0
(2825 3775);
DISPLAY 0.872340 (2825 3775);
PAINT GREEN (2825 3775);
DISPLAY INVISIBLE (2825 3775);
FORCEPROP 1 LAST HDL_TAP TRUE
J 0
(3150 3600);
DISPLAY 0.872340 (3150 3600);
DISPLAY INVISIBLE (3150 3600);
FORCEPROP 1 LAST PATH I349
J 0
(2823 3725);
DISPLAY 0.872340 (2823 3725);
PAINT GREEN (2823 3725);
DISPLAY INVISIBLE (2823 3725);
FORCEADD TAP..1
(2825 3825);
FORCEPROP 3 LASTPIN (2775 3825) SIG_NAME P5E_CPU0_PE2_TX_DP<15>
J 0
(2785 3835);
DISPLAY 0.659574 (2785 3835);
PAINT MONO (2785 3835);
DISPLAY INVISIBLE (2785 3835);
FORCEPROP 1 LASTPIN (2775 3825) BN 15
J 0
(2763 3833);
DISPLAY 0.680851 (2763 3833);
PAINT GREEN (2763 3833);
FORCEPROP 2 LAST CDS_LIB standard
J 0
(2825 3825);
DISPLAY INVISIBLE (2825 3825);
FORCEPROP 1 LAST BODY_TYPE PLUMBING
J 0
(2825 3875);
DISPLAY 0.872340 (2825 3875);
PAINT GREEN (2825 3875);
DISPLAY INVISIBLE (2825 3875);
FORCEPROP 1 LAST HDL_TAP TRUE
J 0
(3150 3700);
DISPLAY 0.872340 (3150 3700);
DISPLAY INVISIBLE (3150 3700);
FORCEPROP 1 LAST PATH I350
J 0
(2823 3825);
DISPLAY 0.872340 (2823 3825);
PAINT GREEN (2823 3825);
DISPLAY INVISIBLE (2823 3825);
FORCEADD OFFPAGE..2
(3925 3000);
FORCEPROP 2 LAST $XR0 173 
J 0
(4114 3000);
DISPLAY 0.638298 (4114 3000);
PAINT MONO (4114 3000);
FORCEPROP 2 LAST CDS_LIB standard
J 0
(3925 3000);
PAINT MONO (3925 3000);
DISPLAY INVISIBLE (3925 3000);
FORCEPROP 1 LAST OFFPAGE TRUE
J 0
(4250 2875);
DISPLAY 1.170213 (4250 2875);
PAINT GREEN (4250 2875);
DISPLAY INVISIBLE (4250 2875);
FORCEPROP 1 LAST COMMENT_BODY TRUE
J 0
(3880 2905);
DISPLAY 1.170213 (3880 2905);
PAINT GREEN (3880 2905);
DISPLAY INVISIBLE (3880 2905);
FORCEPROP 2 LAST PATH I351
J 0
(4125 3050);
DISPLAY 1.021277 (4125 3050);
DISPLAY INVISIBLE (4125 3050);
FORCEADD OFFPAGE..2
(3925 3850);
FORCEPROP 2 LAST $XR0 173 
J 0
(4114 3850);
DISPLAY 0.638298 (4114 3850);
PAINT MONO (4114 3850);
FORCEPROP 2 LAST CDS_LIB standard
J 0
(3925 3850);
PAINT MONO (3925 3850);
DISPLAY INVISIBLE (3925 3850);
FORCEPROP 1 LAST OFFPAGE TRUE
J 0
(4250 3725);
DISPLAY 1.170213 (4250 3725);
PAINT GREEN (4250 3725);
DISPLAY INVISIBLE (4250 3725);
FORCEPROP 1 LAST COMMENT_BODY TRUE
J 0
(3880 3755);
DISPLAY 1.170213 (3880 3755);
PAINT GREEN (3880 3755);
DISPLAY INVISIBLE (3880 3755);
FORCEPROP 2 LAST PATH I352
J 0
(4125 3900);
DISPLAY 1.021277 (4125 3900);
DISPLAY INVISIBLE (4125 3900);
FORCEADD TAP..1
R 2
(-600 2225);
FORCEPROP 3 LASTPIN (-550 2225) SIG_NAME P5E_CPU0_PE2_RX_DN<0>
J 0
(-540 2235);
DISPLAY 0.659574 (-540 2235);
PAINT MONO (-540 2235);
DISPLAY INVISIBLE (-540 2235);
FORCEPROP 1 LASTPIN (-550 2225) BN 0
J 2
(-538 2233);
DISPLAY 0.680851 (-538 2233);
PAINT GREEN (-538 2233);
FORCEPROP 2 LAST CDS_LIB standard
J 0
(-600 2225);
DISPLAY INVISIBLE (-600 2225);
FORCEPROP 1 LAST BODY_TYPE PLUMBING
J 2
(-600 2275);
DISPLAY 0.872340 (-600 2275);
PAINT GREEN (-600 2275);
DISPLAY INVISIBLE (-600 2275);
FORCEPROP 1 LAST HDL_TAP TRUE
J 2
(-925 2100);
DISPLAY 0.872340 (-925 2100);
DISPLAY INVISIBLE (-925 2100);
FORCEPROP 1 LAST PATH I37
J 2
(-598 2225);
DISPLAY 0.872340 (-598 2225);
PAINT GREEN (-598 2225);
DISPLAY INVISIBLE (-598 2225);
FORCEADD TAP..1
R 2
(-600 2275);
FORCEPROP 3 LASTPIN (-550 2275) SIG_NAME P5E_CPU0_PE2_RX_DN<1>
J 0
(-540 2285);
DISPLAY 0.659574 (-540 2285);
PAINT MONO (-540 2285);
DISPLAY INVISIBLE (-540 2285);
FORCEPROP 1 LASTPIN (-550 2275) BN 1
J 2
(-538 2283);
DISPLAY 0.680851 (-538 2283);
PAINT GREEN (-538 2283);
FORCEPROP 2 LAST CDS_LIB standard
J 0
(-600 2275);
DISPLAY INVISIBLE (-600 2275);
FORCEPROP 1 LAST BODY_TYPE PLUMBING
J 2
(-600 2325);
DISPLAY 0.872340 (-600 2325);
PAINT GREEN (-600 2325);
DISPLAY INVISIBLE (-600 2325);
FORCEPROP 1 LAST HDL_TAP TRUE
J 2
(-925 2150);
DISPLAY 0.872340 (-925 2150);
DISPLAY INVISIBLE (-925 2150);
FORCEPROP 1 LAST PATH I38
J 2
(-598 2275);
DISPLAY 0.872340 (-598 2275);
PAINT GREEN (-598 2275);
DISPLAY INVISIBLE (-598 2275);
FORCEADD TAP..1
R 2
(-600 2325);
FORCEPROP 3 LASTPIN (-550 2325) SIG_NAME P5E_CPU0_PE2_RX_DN<2>
J 0
(-540 2335);
DISPLAY 0.659574 (-540 2335);
PAINT MONO (-540 2335);
DISPLAY INVISIBLE (-540 2335);
FORCEPROP 1 LASTPIN (-550 2325) BN 2
J 2
(-538 2333);
DISPLAY 0.680851 (-538 2333);
PAINT GREEN (-538 2333);
FORCEPROP 2 LAST CDS_LIB standard
J 0
(-600 2325);
DISPLAY INVISIBLE (-600 2325);
FORCEPROP 1 LAST BODY_TYPE PLUMBING
J 2
(-600 2375);
DISPLAY 0.872340 (-600 2375);
PAINT GREEN (-600 2375);
DISPLAY INVISIBLE (-600 2375);
FORCEPROP 1 LAST HDL_TAP TRUE
J 2
(-925 2200);
DISPLAY 0.872340 (-925 2200);
DISPLAY INVISIBLE (-925 2200);
FORCEPROP 1 LAST PATH I39
J 2
(-598 2325);
DISPLAY 0.872340 (-598 2325);
PAINT GREEN (-598 2325);
DISPLAY INVISIBLE (-598 2325);
FORCEADD TAP..1
R 2
(-600 2475);
FORCEPROP 3 LASTPIN (-550 2475) SIG_NAME P5E_CPU0_PE2_RX_DN<5>
J 0
(-540 2485);
DISPLAY 0.659574 (-540 2485);
PAINT MONO (-540 2485);
DISPLAY INVISIBLE (-540 2485);
FORCEPROP 1 LASTPIN (-550 2475) BN 5
J 2
(-538 2483);
DISPLAY 0.680851 (-538 2483);
PAINT GREEN (-538 2483);
FORCEPROP 2 LAST CDS_LIB standard
J 0
(-600 2475);
DISPLAY INVISIBLE (-600 2475);
FORCEPROP 1 LAST BODY_TYPE PLUMBING
J 2
(-600 2525);
DISPLAY 0.872340 (-600 2525);
PAINT GREEN (-600 2525);
DISPLAY INVISIBLE (-600 2525);
FORCEPROP 1 LAST HDL_TAP TRUE
J 2
(-925 2350);
DISPLAY 0.872340 (-925 2350);
DISPLAY INVISIBLE (-925 2350);
FORCEPROP 1 LAST PATH I40
J 2
(-598 2475);
DISPLAY 0.872340 (-598 2475);
PAINT GREEN (-598 2475);
DISPLAY INVISIBLE (-598 2475);
FORCEADD TAP..1
R 2
(-600 2425);
FORCEPROP 3 LASTPIN (-550 2425) SIG_NAME P5E_CPU0_PE2_RX_DN<4>
J 0
(-540 2435);
DISPLAY 0.659574 (-540 2435);
PAINT MONO (-540 2435);
DISPLAY INVISIBLE (-540 2435);
FORCEPROP 1 LASTPIN (-550 2425) BN 4
J 2
(-538 2433);
DISPLAY 0.680851 (-538 2433);
PAINT GREEN (-538 2433);
FORCEPROP 2 LAST CDS_LIB standard
J 0
(-600 2425);
DISPLAY INVISIBLE (-600 2425);
FORCEPROP 1 LAST BODY_TYPE PLUMBING
J 2
(-600 2475);
DISPLAY 0.872340 (-600 2475);
PAINT GREEN (-600 2475);
DISPLAY INVISIBLE (-600 2475);
FORCEPROP 1 LAST HDL_TAP TRUE
J 2
(-925 2300);
DISPLAY 0.872340 (-925 2300);
DISPLAY INVISIBLE (-925 2300);
FORCEPROP 1 LAST PATH I41
J 2
(-598 2425);
DISPLAY 0.872340 (-598 2425);
PAINT GREEN (-598 2425);
DISPLAY INVISIBLE (-598 2425);
FORCEADD TAP..1
R 2
(-600 2375);
FORCEPROP 3 LASTPIN (-550 2375) SIG_NAME P5E_CPU0_PE2_RX_DN<3>
J 0
(-540 2385);
DISPLAY 0.659574 (-540 2385);
PAINT MONO (-540 2385);
DISPLAY INVISIBLE (-540 2385);
FORCEPROP 1 LASTPIN (-550 2375) BN 3
J 2
(-538 2383);
DISPLAY 0.680851 (-538 2383);
PAINT GREEN (-538 2383);
FORCEPROP 2 LAST CDS_LIB standard
J 0
(-600 2375);
DISPLAY INVISIBLE (-600 2375);
FORCEPROP 1 LAST BODY_TYPE PLUMBING
J 2
(-600 2425);
DISPLAY 0.872340 (-600 2425);
PAINT GREEN (-600 2425);
DISPLAY INVISIBLE (-600 2425);
FORCEPROP 1 LAST HDL_TAP TRUE
J 2
(-925 2250);
DISPLAY 0.872340 (-925 2250);
DISPLAY INVISIBLE (-925 2250);
FORCEPROP 1 LAST PATH I42
J 2
(-598 2375);
DISPLAY 0.872340 (-598 2375);
PAINT GREEN (-598 2375);
DISPLAY INVISIBLE (-598 2375);
FORCEADD TAP..1
R 2
(-600 2575);
FORCEPROP 3 LASTPIN (-550 2575) SIG_NAME P5E_CPU0_PE2_RX_DN<7>
J 0
(-540 2585);
DISPLAY 0.659574 (-540 2585);
PAINT MONO (-540 2585);
DISPLAY INVISIBLE (-540 2585);
FORCEPROP 1 LASTPIN (-550 2575) BN 7
J 2
(-538 2583);
DISPLAY 0.680851 (-538 2583);
PAINT GREEN (-538 2583);
FORCEPROP 2 LAST CDS_LIB standard
J 0
(-600 2575);
DISPLAY INVISIBLE (-600 2575);
FORCEPROP 1 LAST BODY_TYPE PLUMBING
J 2
(-600 2625);
DISPLAY 0.872340 (-600 2625);
PAINT GREEN (-600 2625);
DISPLAY INVISIBLE (-600 2625);
FORCEPROP 1 LAST HDL_TAP TRUE
J 2
(-925 2450);
DISPLAY 0.872340 (-925 2450);
DISPLAY INVISIBLE (-925 2450);
FORCEPROP 1 LAST PATH I43
J 2
(-598 2575);
DISPLAY 0.872340 (-598 2575);
PAINT GREEN (-598 2575);
DISPLAY INVISIBLE (-598 2575);
FORCEADD TAP..1
R 2
(-600 2525);
FORCEPROP 3 LASTPIN (-550 2525) SIG_NAME P5E_CPU0_PE2_RX_DN<6>
J 0
(-540 2535);
DISPLAY 0.659574 (-540 2535);
PAINT MONO (-540 2535);
DISPLAY INVISIBLE (-540 2535);
FORCEPROP 1 LASTPIN (-550 2525) BN 6
J 2
(-538 2533);
DISPLAY 0.680851 (-538 2533);
PAINT GREEN (-538 2533);
FORCEPROP 2 LAST CDS_LIB standard
J 0
(-600 2525);
DISPLAY INVISIBLE (-600 2525);
FORCEPROP 1 LAST BODY_TYPE PLUMBING
J 2
(-600 2575);
DISPLAY 0.872340 (-600 2575);
PAINT GREEN (-600 2575);
DISPLAY INVISIBLE (-600 2575);
FORCEPROP 1 LAST HDL_TAP TRUE
J 2
(-925 2400);
DISPLAY 0.872340 (-925 2400);
DISPLAY INVISIBLE (-925 2400);
FORCEPROP 1 LAST PATH I44
J 2
(-598 2525);
DISPLAY 0.872340 (-598 2525);
PAINT GREEN (-598 2525);
DISPLAY INVISIBLE (-598 2525);
FORCEADD TAP..1
R 2
(-600 2725);
FORCEPROP 3 LASTPIN (-550 2725) SIG_NAME P5E_CPU0_PE2_RX_DN<10>
J 0
(-540 2735);
DISPLAY 0.659574 (-540 2735);
PAINT MONO (-540 2735);
DISPLAY INVISIBLE (-540 2735);
FORCEPROP 1 LASTPIN (-550 2725) BN 10
J 2
(-538 2733);
DISPLAY 0.680851 (-538 2733);
PAINT GREEN (-538 2733);
FORCEPROP 2 LAST CDS_LIB standard
J 0
(-600 2725);
DISPLAY INVISIBLE (-600 2725);
FORCEPROP 1 LAST BODY_TYPE PLUMBING
J 2
(-600 2775);
DISPLAY 0.872340 (-600 2775);
PAINT GREEN (-600 2775);
DISPLAY INVISIBLE (-600 2775);
FORCEPROP 1 LAST HDL_TAP TRUE
J 2
(-925 2600);
DISPLAY 0.872340 (-925 2600);
DISPLAY INVISIBLE (-925 2600);
FORCEPROP 1 LAST PATH I45
J 2
(-598 2725);
DISPLAY 0.872340 (-598 2725);
PAINT GREEN (-598 2725);
DISPLAY INVISIBLE (-598 2725);
FORCEADD TAP..1
R 2
(-600 2625);
FORCEPROP 3 LASTPIN (-550 2625) SIG_NAME P5E_CPU0_PE2_RX_DN<8>
J 0
(-540 2635);
DISPLAY 0.659574 (-540 2635);
PAINT MONO (-540 2635);
DISPLAY INVISIBLE (-540 2635);
FORCEPROP 1 LASTPIN (-550 2625) BN 8
J 2
(-538 2633);
DISPLAY 0.680851 (-538 2633);
PAINT GREEN (-538 2633);
FORCEPROP 2 LAST CDS_LIB standard
J 0
(-600 2625);
DISPLAY INVISIBLE (-600 2625);
FORCEPROP 1 LAST BODY_TYPE PLUMBING
J 2
(-600 2675);
DISPLAY 0.872340 (-600 2675);
PAINT GREEN (-600 2675);
DISPLAY INVISIBLE (-600 2675);
FORCEPROP 1 LAST HDL_TAP TRUE
J 2
(-925 2500);
DISPLAY 0.872340 (-925 2500);
DISPLAY INVISIBLE (-925 2500);
FORCEPROP 1 LAST PATH I46
J 2
(-598 2625);
DISPLAY 0.872340 (-598 2625);
PAINT GREEN (-598 2625);
DISPLAY INVISIBLE (-598 2625);
FORCEADD TAP..1
R 2
(-600 2675);
FORCEPROP 3 LASTPIN (-550 2675) SIG_NAME P5E_CPU0_PE2_RX_DN<9>
J 0
(-540 2685);
DISPLAY 0.659574 (-540 2685);
PAINT MONO (-540 2685);
DISPLAY INVISIBLE (-540 2685);
FORCEPROP 1 LASTPIN (-550 2675) BN 9
J 2
(-538 2683);
DISPLAY 0.680851 (-538 2683);
PAINT GREEN (-538 2683);
FORCEPROP 2 LAST CDS_LIB standard
J 0
(-600 2675);
DISPLAY INVISIBLE (-600 2675);
FORCEPROP 1 LAST BODY_TYPE PLUMBING
J 2
(-600 2725);
DISPLAY 0.872340 (-600 2725);
PAINT GREEN (-600 2725);
DISPLAY INVISIBLE (-600 2725);
FORCEPROP 1 LAST HDL_TAP TRUE
J 2
(-925 2550);
DISPLAY 0.872340 (-925 2550);
DISPLAY INVISIBLE (-925 2550);
FORCEPROP 1 LAST PATH I47
J 2
(-598 2675);
DISPLAY 0.872340 (-598 2675);
PAINT GREEN (-598 2675);
DISPLAY INVISIBLE (-598 2675);
FORCEADD TAP..1
R 2
(-600 2775);
FORCEPROP 3 LASTPIN (-550 2775) SIG_NAME P5E_CPU0_PE2_RX_DN<11>
J 0
(-540 2785);
DISPLAY 0.659574 (-540 2785);
PAINT MONO (-540 2785);
DISPLAY INVISIBLE (-540 2785);
FORCEPROP 1 LASTPIN (-550 2775) BN 11
J 2
(-538 2783);
DISPLAY 0.680851 (-538 2783);
PAINT GREEN (-538 2783);
FORCEPROP 2 LAST CDS_LIB standard
J 0
(-600 2775);
DISPLAY INVISIBLE (-600 2775);
FORCEPROP 1 LAST BODY_TYPE PLUMBING
J 2
(-600 2825);
DISPLAY 0.872340 (-600 2825);
PAINT GREEN (-600 2825);
DISPLAY INVISIBLE (-600 2825);
FORCEPROP 1 LAST HDL_TAP TRUE
J 2
(-925 2650);
DISPLAY 0.872340 (-925 2650);
DISPLAY INVISIBLE (-925 2650);
FORCEPROP 1 LAST PATH I48
J 2
(-598 2775);
DISPLAY 0.872340 (-598 2775);
PAINT GREEN (-598 2775);
DISPLAY INVISIBLE (-598 2775);
FORCEADD TAP..1
R 2
(-600 2825);
FORCEPROP 3 LASTPIN (-550 2825) SIG_NAME P5E_CPU0_PE2_RX_DN<12>
J 0
(-540 2835);
DISPLAY 0.659574 (-540 2835);
PAINT MONO (-540 2835);
DISPLAY INVISIBLE (-540 2835);
FORCEPROP 1 LASTPIN (-550 2825) BN 12
J 2
(-538 2833);
DISPLAY 0.680851 (-538 2833);
PAINT GREEN (-538 2833);
FORCEPROP 2 LAST CDS_LIB standard
J 0
(-600 2825);
DISPLAY INVISIBLE (-600 2825);
FORCEPROP 1 LAST BODY_TYPE PLUMBING
J 2
(-600 2875);
DISPLAY 0.872340 (-600 2875);
PAINT GREEN (-600 2875);
DISPLAY INVISIBLE (-600 2875);
FORCEPROP 1 LAST HDL_TAP TRUE
J 2
(-925 2700);
DISPLAY 0.872340 (-925 2700);
DISPLAY INVISIBLE (-925 2700);
FORCEPROP 1 LAST PATH I49
J 2
(-598 2825);
DISPLAY 0.872340 (-598 2825);
PAINT GREEN (-598 2825);
DISPLAY INVISIBLE (-598 2825);
FORCEADD TAP..1
R 2
(-600 2925);
FORCEPROP 3 LASTPIN (-550 2925) SIG_NAME P5E_CPU0_PE2_RX_DN<14>
J 0
(-540 2935);
DISPLAY 0.659574 (-540 2935);
PAINT MONO (-540 2935);
DISPLAY INVISIBLE (-540 2935);
FORCEPROP 1 LASTPIN (-550 2925) BN 14
J 2
(-538 2933);
DISPLAY 0.680851 (-538 2933);
PAINT GREEN (-538 2933);
FORCEPROP 2 LAST CDS_LIB standard
J 0
(-600 2925);
DISPLAY INVISIBLE (-600 2925);
FORCEPROP 1 LAST BODY_TYPE PLUMBING
J 2
(-600 2975);
DISPLAY 0.872340 (-600 2975);
PAINT GREEN (-600 2975);
DISPLAY INVISIBLE (-600 2975);
FORCEPROP 1 LAST HDL_TAP TRUE
J 2
(-925 2800);
DISPLAY 0.872340 (-925 2800);
DISPLAY INVISIBLE (-925 2800);
FORCEPROP 1 LAST PATH I50
J 2
(-598 2925);
DISPLAY 0.872340 (-598 2925);
PAINT GREEN (-598 2925);
DISPLAY INVISIBLE (-598 2925);
FORCEADD TAP..1
R 2
(-600 2975);
FORCEPROP 3 LASTPIN (-550 2975) SIG_NAME P5E_CPU0_PE2_RX_DN<15>
J 0
(-540 2985);
DISPLAY 0.659574 (-540 2985);
PAINT MONO (-540 2985);
DISPLAY INVISIBLE (-540 2985);
FORCEPROP 1 LASTPIN (-550 2975) BN 15
J 2
(-538 2983);
DISPLAY 0.680851 (-538 2983);
PAINT GREEN (-538 2983);
FORCEPROP 2 LAST CDS_LIB standard
J 0
(-600 2975);
DISPLAY INVISIBLE (-600 2975);
FORCEPROP 1 LAST BODY_TYPE PLUMBING
J 2
(-600 3025);
DISPLAY 0.872340 (-600 3025);
PAINT GREEN (-600 3025);
DISPLAY INVISIBLE (-600 3025);
FORCEPROP 1 LAST HDL_TAP TRUE
J 2
(-925 2850);
DISPLAY 0.872340 (-925 2850);
DISPLAY INVISIBLE (-925 2850);
FORCEPROP 1 LAST PATH I51
J 2
(-598 2975);
DISPLAY 0.872340 (-598 2975);
PAINT GREEN (-598 2975);
DISPLAY INVISIBLE (-598 2975);
FORCEADD TAP..1
R 2
(-600 2875);
FORCEPROP 3 LASTPIN (-550 2875) SIG_NAME P5E_CPU0_PE2_RX_DN<13>
J 0
(-540 2885);
DISPLAY 0.659574 (-540 2885);
PAINT MONO (-540 2885);
DISPLAY INVISIBLE (-540 2885);
FORCEPROP 1 LASTPIN (-550 2875) BN 13
J 2
(-538 2883);
DISPLAY 0.680851 (-538 2883);
PAINT GREEN (-538 2883);
FORCEPROP 2 LAST CDS_LIB standard
J 0
(-600 2875);
DISPLAY INVISIBLE (-600 2875);
FORCEPROP 1 LAST BODY_TYPE PLUMBING
J 2
(-600 2925);
DISPLAY 0.872340 (-600 2925);
PAINT GREEN (-600 2925);
DISPLAY INVISIBLE (-600 2925);
FORCEPROP 1 LAST HDL_TAP TRUE
J 2
(-925 2750);
DISPLAY 0.872340 (-925 2750);
DISPLAY INVISIBLE (-925 2750);
FORCEPROP 1 LAST PATH I52
J 2
(-598 2875);
DISPLAY 0.872340 (-598 2875);
PAINT GREEN (-598 2875);
DISPLAY INVISIBLE (-598 2875);
FORCEADD TAP..1
R 2
(-600 3075);
FORCEPROP 3 LASTPIN (-550 3075) SIG_NAME P5E_CPU0_PE2_RX_DP<0>
J 0
(-540 3085);
DISPLAY 0.659574 (-540 3085);
PAINT MONO (-540 3085);
DISPLAY INVISIBLE (-540 3085);
FORCEPROP 1 LASTPIN (-550 3075) BN 0
J 2
(-538 3083);
DISPLAY 0.680851 (-538 3083);
PAINT GREEN (-538 3083);
FORCEPROP 2 LAST CDS_LIB standard
J 0
(-600 3075);
DISPLAY INVISIBLE (-600 3075);
FORCEPROP 1 LAST BODY_TYPE PLUMBING
J 2
(-600 3125);
DISPLAY 0.872340 (-600 3125);
PAINT GREEN (-600 3125);
DISPLAY INVISIBLE (-600 3125);
FORCEPROP 1 LAST HDL_TAP TRUE
J 2
(-925 2950);
DISPLAY 0.872340 (-925 2950);
DISPLAY INVISIBLE (-925 2950);
FORCEPROP 1 LAST PATH I53
J 2
(-598 3075);
DISPLAY 0.872340 (-598 3075);
PAINT GREEN (-598 3075);
DISPLAY INVISIBLE (-598 3075);
FORCEADD TAP..1
R 2
(-600 3125);
FORCEPROP 3 LASTPIN (-550 3125) SIG_NAME P5E_CPU0_PE2_RX_DP<1>
J 0
(-540 3135);
DISPLAY 0.659574 (-540 3135);
PAINT MONO (-540 3135);
DISPLAY INVISIBLE (-540 3135);
FORCEPROP 1 LASTPIN (-550 3125) BN 1
J 2
(-538 3133);
DISPLAY 0.680851 (-538 3133);
PAINT GREEN (-538 3133);
FORCEPROP 2 LAST CDS_LIB standard
J 0
(-600 3125);
DISPLAY INVISIBLE (-600 3125);
FORCEPROP 1 LAST BODY_TYPE PLUMBING
J 2
(-600 3175);
DISPLAY 0.872340 (-600 3175);
PAINT GREEN (-600 3175);
DISPLAY INVISIBLE (-600 3175);
FORCEPROP 1 LAST HDL_TAP TRUE
J 2
(-925 3000);
DISPLAY 0.872340 (-925 3000);
DISPLAY INVISIBLE (-925 3000);
FORCEPROP 1 LAST PATH I54
J 2
(-598 3125);
DISPLAY 0.872340 (-598 3125);
PAINT GREEN (-598 3125);
DISPLAY INVISIBLE (-598 3125);
FORCEADD TAP..1
R 2
(-600 3175);
FORCEPROP 3 LASTPIN (-550 3175) SIG_NAME P5E_CPU0_PE2_RX_DP<2>
J 0
(-540 3185);
DISPLAY 0.659574 (-540 3185);
PAINT MONO (-540 3185);
DISPLAY INVISIBLE (-540 3185);
FORCEPROP 1 LASTPIN (-550 3175) BN 2
J 2
(-538 3183);
DISPLAY 0.680851 (-538 3183);
PAINT GREEN (-538 3183);
FORCEPROP 2 LAST CDS_LIB standard
J 0
(-600 3175);
DISPLAY INVISIBLE (-600 3175);
FORCEPROP 1 LAST BODY_TYPE PLUMBING
J 2
(-600 3225);
DISPLAY 0.872340 (-600 3225);
PAINT GREEN (-600 3225);
DISPLAY INVISIBLE (-600 3225);
FORCEPROP 1 LAST HDL_TAP TRUE
J 2
(-925 3050);
DISPLAY 0.872340 (-925 3050);
DISPLAY INVISIBLE (-925 3050);
FORCEPROP 1 LAST PATH I55
J 2
(-598 3175);
DISPLAY 0.872340 (-598 3175);
PAINT GREEN (-598 3175);
DISPLAY INVISIBLE (-598 3175);
FORCEADD TAP..1
R 2
(-600 3225);
FORCEPROP 3 LASTPIN (-550 3225) SIG_NAME P5E_CPU0_PE2_RX_DP<3>
J 0
(-540 3235);
DISPLAY 0.659574 (-540 3235);
PAINT MONO (-540 3235);
DISPLAY INVISIBLE (-540 3235);
FORCEPROP 1 LASTPIN (-550 3225) BN 3
J 2
(-538 3233);
DISPLAY 0.680851 (-538 3233);
PAINT GREEN (-538 3233);
FORCEPROP 2 LAST CDS_LIB standard
J 0
(-600 3225);
DISPLAY INVISIBLE (-600 3225);
FORCEPROP 1 LAST BODY_TYPE PLUMBING
J 2
(-600 3275);
DISPLAY 0.872340 (-600 3275);
PAINT GREEN (-600 3275);
DISPLAY INVISIBLE (-600 3275);
FORCEPROP 1 LAST HDL_TAP TRUE
J 2
(-925 3100);
DISPLAY 0.872340 (-925 3100);
DISPLAY INVISIBLE (-925 3100);
FORCEPROP 1 LAST PATH I56
J 2
(-598 3225);
DISPLAY 0.872340 (-598 3225);
PAINT GREEN (-598 3225);
DISPLAY INVISIBLE (-598 3225);
FORCEADD TAP..1
R 2
(-600 3375);
FORCEPROP 3 LASTPIN (-550 3375) SIG_NAME P5E_CPU0_PE2_RX_DP<6>
J 0
(-540 3385);
DISPLAY 0.659574 (-540 3385);
PAINT MONO (-540 3385);
DISPLAY INVISIBLE (-540 3385);
FORCEPROP 1 LASTPIN (-550 3375) BN 6
J 2
(-538 3383);
DISPLAY 0.680851 (-538 3383);
PAINT GREEN (-538 3383);
FORCEPROP 2 LAST CDS_LIB standard
J 0
(-600 3375);
DISPLAY INVISIBLE (-600 3375);
FORCEPROP 1 LAST BODY_TYPE PLUMBING
J 2
(-600 3425);
DISPLAY 0.872340 (-600 3425);
PAINT GREEN (-600 3425);
DISPLAY INVISIBLE (-600 3425);
FORCEPROP 1 LAST HDL_TAP TRUE
J 2
(-925 3250);
DISPLAY 0.872340 (-925 3250);
DISPLAY INVISIBLE (-925 3250);
FORCEPROP 1 LAST PATH I57
J 2
(-598 3375);
DISPLAY 0.872340 (-598 3375);
PAINT GREEN (-598 3375);
DISPLAY INVISIBLE (-598 3375);
FORCEADD TAP..1
R 2
(-600 3325);
FORCEPROP 3 LASTPIN (-550 3325) SIG_NAME P5E_CPU0_PE2_RX_DP<5>
J 0
(-540 3335);
DISPLAY 0.659574 (-540 3335);
PAINT MONO (-540 3335);
DISPLAY INVISIBLE (-540 3335);
FORCEPROP 1 LASTPIN (-550 3325) BN 5
J 2
(-538 3333);
DISPLAY 0.680851 (-538 3333);
PAINT GREEN (-538 3333);
FORCEPROP 2 LAST CDS_LIB standard
J 0
(-600 3325);
DISPLAY INVISIBLE (-600 3325);
FORCEPROP 1 LAST BODY_TYPE PLUMBING
J 2
(-600 3375);
DISPLAY 0.872340 (-600 3375);
PAINT GREEN (-600 3375);
DISPLAY INVISIBLE (-600 3375);
FORCEPROP 1 LAST HDL_TAP TRUE
J 2
(-925 3200);
DISPLAY 0.872340 (-925 3200);
DISPLAY INVISIBLE (-925 3200);
FORCEPROP 1 LAST PATH I58
J 2
(-598 3325);
DISPLAY 0.872340 (-598 3325);
PAINT GREEN (-598 3325);
DISPLAY INVISIBLE (-598 3325);
FORCEADD TAP..1
R 2
(-600 3275);
FORCEPROP 3 LASTPIN (-550 3275) SIG_NAME P5E_CPU0_PE2_RX_DP<4>
J 0
(-540 3285);
DISPLAY 0.659574 (-540 3285);
PAINT MONO (-540 3285);
DISPLAY INVISIBLE (-540 3285);
FORCEPROP 1 LASTPIN (-550 3275) BN 4
J 2
(-538 3283);
DISPLAY 0.680851 (-538 3283);
PAINT GREEN (-538 3283);
FORCEPROP 2 LAST CDS_LIB standard
J 0
(-600 3275);
DISPLAY INVISIBLE (-600 3275);
FORCEPROP 1 LAST BODY_TYPE PLUMBING
J 2
(-600 3325);
DISPLAY 0.872340 (-600 3325);
PAINT GREEN (-600 3325);
DISPLAY INVISIBLE (-600 3325);
FORCEPROP 1 LAST HDL_TAP TRUE
J 2
(-925 3150);
DISPLAY 0.872340 (-925 3150);
DISPLAY INVISIBLE (-925 3150);
FORCEPROP 1 LAST PATH I59
J 2
(-598 3275);
DISPLAY 0.872340 (-598 3275);
PAINT GREEN (-598 3275);
DISPLAY INVISIBLE (-598 3275);
FORCEADD TAP..1
R 2
(-600 3475);
FORCEPROP 3 LASTPIN (-550 3475) SIG_NAME P5E_CPU0_PE2_RX_DP<8>
J 0
(-540 3485);
DISPLAY 0.659574 (-540 3485);
PAINT MONO (-540 3485);
DISPLAY INVISIBLE (-540 3485);
FORCEPROP 1 LASTPIN (-550 3475) BN 8
J 2
(-538 3483);
DISPLAY 0.680851 (-538 3483);
PAINT GREEN (-538 3483);
FORCEPROP 2 LAST CDS_LIB standard
J 0
(-600 3475);
DISPLAY INVISIBLE (-600 3475);
FORCEPROP 1 LAST BODY_TYPE PLUMBING
J 2
(-600 3525);
DISPLAY 0.872340 (-600 3525);
PAINT GREEN (-600 3525);
DISPLAY INVISIBLE (-600 3525);
FORCEPROP 1 LAST HDL_TAP TRUE
J 2
(-925 3350);
DISPLAY 0.872340 (-925 3350);
DISPLAY INVISIBLE (-925 3350);
FORCEPROP 1 LAST PATH I60
J 2
(-598 3475);
DISPLAY 0.872340 (-598 3475);
PAINT GREEN (-598 3475);
DISPLAY INVISIBLE (-598 3475);
FORCEADD TAP..1
R 2
(-600 3425);
FORCEPROP 3 LASTPIN (-550 3425) SIG_NAME P5E_CPU0_PE2_RX_DP<7>
J 0
(-540 3435);
DISPLAY 0.659574 (-540 3435);
PAINT MONO (-540 3435);
DISPLAY INVISIBLE (-540 3435);
FORCEPROP 1 LASTPIN (-550 3425) BN 7
J 2
(-538 3433);
DISPLAY 0.680851 (-538 3433);
PAINT GREEN (-538 3433);
FORCEPROP 2 LAST CDS_LIB standard
J 0
(-600 3425);
DISPLAY INVISIBLE (-600 3425);
FORCEPROP 1 LAST BODY_TYPE PLUMBING
J 2
(-600 3475);
DISPLAY 0.872340 (-600 3475);
PAINT GREEN (-600 3475);
DISPLAY INVISIBLE (-600 3475);
FORCEPROP 1 LAST HDL_TAP TRUE
J 2
(-925 3300);
DISPLAY 0.872340 (-925 3300);
DISPLAY INVISIBLE (-925 3300);
FORCEPROP 1 LAST PATH I61
J 2
(-598 3425);
DISPLAY 0.872340 (-598 3425);
PAINT GREEN (-598 3425);
DISPLAY INVISIBLE (-598 3425);
FORCEADD TAP..1
R 2
(-600 3625);
FORCEPROP 3 LASTPIN (-550 3625) SIG_NAME P5E_CPU0_PE2_RX_DP<11>
J 0
(-540 3635);
DISPLAY 0.659574 (-540 3635);
PAINT MONO (-540 3635);
DISPLAY INVISIBLE (-540 3635);
FORCEPROP 1 LASTPIN (-550 3625) BN 11
J 2
(-538 3633);
DISPLAY 0.680851 (-538 3633);
PAINT GREEN (-538 3633);
FORCEPROP 2 LAST CDS_LIB standard
J 0
(-600 3625);
DISPLAY INVISIBLE (-600 3625);
FORCEPROP 1 LAST BODY_TYPE PLUMBING
J 2
(-600 3675);
DISPLAY 0.872340 (-600 3675);
PAINT GREEN (-600 3675);
DISPLAY INVISIBLE (-600 3675);
FORCEPROP 1 LAST HDL_TAP TRUE
J 2
(-925 3500);
DISPLAY 0.872340 (-925 3500);
DISPLAY INVISIBLE (-925 3500);
FORCEPROP 1 LAST PATH I62
J 2
(-598 3625);
DISPLAY 0.872340 (-598 3625);
PAINT GREEN (-598 3625);
DISPLAY INVISIBLE (-598 3625);
FORCEADD TAP..1
R 2
(-600 3525);
FORCEPROP 3 LASTPIN (-550 3525) SIG_NAME P5E_CPU0_PE2_RX_DP<9>
J 0
(-540 3535);
DISPLAY 0.659574 (-540 3535);
PAINT MONO (-540 3535);
DISPLAY INVISIBLE (-540 3535);
FORCEPROP 1 LASTPIN (-550 3525) BN 9
J 2
(-538 3533);
DISPLAY 0.680851 (-538 3533);
PAINT GREEN (-538 3533);
FORCEPROP 2 LAST CDS_LIB standard
J 0
(-600 3525);
DISPLAY INVISIBLE (-600 3525);
FORCEPROP 1 LAST BODY_TYPE PLUMBING
J 2
(-600 3575);
DISPLAY 0.872340 (-600 3575);
PAINT GREEN (-600 3575);
DISPLAY INVISIBLE (-600 3575);
FORCEPROP 1 LAST HDL_TAP TRUE
J 2
(-925 3400);
DISPLAY 0.872340 (-925 3400);
DISPLAY INVISIBLE (-925 3400);
FORCEPROP 1 LAST PATH I63
J 2
(-598 3525);
DISPLAY 0.872340 (-598 3525);
PAINT GREEN (-598 3525);
DISPLAY INVISIBLE (-598 3525);
FORCEADD TAP..1
R 2
(-600 3575);
FORCEPROP 3 LASTPIN (-550 3575) SIG_NAME P5E_CPU0_PE2_RX_DP<10>
J 0
(-540 3585);
DISPLAY 0.659574 (-540 3585);
PAINT MONO (-540 3585);
DISPLAY INVISIBLE (-540 3585);
FORCEPROP 1 LASTPIN (-550 3575) BN 10
J 2
(-538 3583);
DISPLAY 0.680851 (-538 3583);
PAINT GREEN (-538 3583);
FORCEPROP 2 LAST CDS_LIB standard
J 0
(-600 3575);
DISPLAY INVISIBLE (-600 3575);
FORCEPROP 1 LAST BODY_TYPE PLUMBING
J 2
(-600 3625);
DISPLAY 0.872340 (-600 3625);
PAINT GREEN (-600 3625);
DISPLAY INVISIBLE (-600 3625);
FORCEPROP 1 LAST HDL_TAP TRUE
J 2
(-925 3450);
DISPLAY 0.872340 (-925 3450);
DISPLAY INVISIBLE (-925 3450);
FORCEPROP 1 LAST PATH I64
J 2
(-598 3575);
DISPLAY 0.872340 (-598 3575);
PAINT GREEN (-598 3575);
DISPLAY INVISIBLE (-598 3575);
FORCEADD TAP..1
R 2
(-600 3675);
FORCEPROP 3 LASTPIN (-550 3675) SIG_NAME P5E_CPU0_PE2_RX_DP<12>
J 0
(-540 3685);
DISPLAY 0.659574 (-540 3685);
PAINT MONO (-540 3685);
DISPLAY INVISIBLE (-540 3685);
FORCEPROP 1 LASTPIN (-550 3675) BN 12
J 2
(-538 3683);
DISPLAY 0.680851 (-538 3683);
PAINT GREEN (-538 3683);
FORCEPROP 2 LAST CDS_LIB standard
J 0
(-600 3675);
DISPLAY INVISIBLE (-600 3675);
FORCEPROP 1 LAST BODY_TYPE PLUMBING
J 2
(-600 3725);
DISPLAY 0.872340 (-600 3725);
PAINT GREEN (-600 3725);
DISPLAY INVISIBLE (-600 3725);
FORCEPROP 1 LAST HDL_TAP TRUE
J 2
(-925 3550);
DISPLAY 0.872340 (-925 3550);
DISPLAY INVISIBLE (-925 3550);
FORCEPROP 1 LAST PATH I65
J 2
(-598 3675);
DISPLAY 0.872340 (-598 3675);
PAINT GREEN (-598 3675);
DISPLAY INVISIBLE (-598 3675);
FORCEADD TAP..1
R 2
(-600 3725);
FORCEPROP 3 LASTPIN (-550 3725) SIG_NAME P5E_CPU0_PE2_RX_DP<13>
J 0
(-540 3735);
DISPLAY 0.659574 (-540 3735);
PAINT MONO (-540 3735);
DISPLAY INVISIBLE (-540 3735);
FORCEPROP 1 LASTPIN (-550 3725) BN 13
J 2
(-538 3733);
DISPLAY 0.680851 (-538 3733);
PAINT GREEN (-538 3733);
FORCEPROP 2 LAST CDS_LIB standard
J 0
(-600 3725);
DISPLAY INVISIBLE (-600 3725);
FORCEPROP 1 LAST BODY_TYPE PLUMBING
J 2
(-600 3775);
DISPLAY 0.872340 (-600 3775);
PAINT GREEN (-600 3775);
DISPLAY INVISIBLE (-600 3775);
FORCEPROP 1 LAST HDL_TAP TRUE
J 2
(-925 3600);
DISPLAY 0.872340 (-925 3600);
DISPLAY INVISIBLE (-925 3600);
FORCEPROP 1 LAST PATH I66
J 2
(-598 3725);
DISPLAY 0.872340 (-598 3725);
PAINT GREEN (-598 3725);
DISPLAY INVISIBLE (-598 3725);
FORCEADD TAP..1
R 2
(-600 3825);
FORCEPROP 3 LASTPIN (-550 3825) SIG_NAME P5E_CPU0_PE2_RX_DP<15>
J 0
(-540 3835);
DISPLAY 0.659574 (-540 3835);
PAINT MONO (-540 3835);
DISPLAY INVISIBLE (-540 3835);
FORCEPROP 1 LASTPIN (-550 3825) BN 15
J 2
(-538 3833);
DISPLAY 0.680851 (-538 3833);
PAINT GREEN (-538 3833);
FORCEPROP 2 LAST CDS_LIB standard
J 0
(-600 3825);
DISPLAY INVISIBLE (-600 3825);
FORCEPROP 1 LAST BODY_TYPE PLUMBING
J 2
(-600 3875);
DISPLAY 0.872340 (-600 3875);
PAINT GREEN (-600 3875);
DISPLAY INVISIBLE (-600 3875);
FORCEPROP 1 LAST HDL_TAP TRUE
J 2
(-925 3700);
DISPLAY 0.872340 (-925 3700);
DISPLAY INVISIBLE (-925 3700);
FORCEPROP 1 LAST PATH I67
J 2
(-598 3825);
DISPLAY 0.872340 (-598 3825);
PAINT GREEN (-598 3825);
DISPLAY INVISIBLE (-598 3825);
FORCEADD TAP..1
R 2
(-600 3775);
FORCEPROP 3 LASTPIN (-550 3775) SIG_NAME P5E_CPU0_PE2_RX_DP<14>
J 0
(-540 3785);
DISPLAY 0.659574 (-540 3785);
PAINT MONO (-540 3785);
DISPLAY INVISIBLE (-540 3785);
FORCEPROP 1 LASTPIN (-550 3775) BN 14
J 2
(-538 3783);
DISPLAY 0.680851 (-538 3783);
PAINT GREEN (-538 3783);
FORCEPROP 2 LAST CDS_LIB standard
J 0
(-600 3775);
DISPLAY INVISIBLE (-600 3775);
FORCEPROP 1 LAST BODY_TYPE PLUMBING
J 2
(-600 3825);
DISPLAY 0.872340 (-600 3825);
PAINT GREEN (-600 3825);
DISPLAY INVISIBLE (-600 3825);
FORCEPROP 1 LAST HDL_TAP TRUE
J 2
(-925 3650);
DISPLAY 0.872340 (-925 3650);
DISPLAY INVISIBLE (-925 3650);
FORCEPROP 1 LAST PATH I68
J 2
(-598 3775);
DISPLAY 0.872340 (-598 3775);
PAINT GREEN (-598 3775);
DISPLAY INVISIBLE (-598 3775);
FORCEADD QUANTA_TITLE_BLOCK_C..1
(5700 -1675);
FORCEPROP 0 LAST CDS_CON_LAST_MODIFIED Fri Aug 25 14:00:15 2023
J 0
(3815 -1660);
PAINT MONO (3815 -1660);
DISPLAY INVISIBLE (3815 -1660);
FORCEPROP 1 LAST CUSTOM_TXT_CDS <CON_LAST_MODIFIED>
J 0
(3815 -1660);
DISPLAY 0.978723 (3815 -1660);
FORCEPROP 2 LAST CUSTOM_TXT_CDS <XR_PAGE_TITLE>
J 0
(-2190 3575);
DISPLAY 0.638298 (-2190 3575);
PAINT PINK (-2190 3575);
DISPLAY INVISIBLE (-2190 3575);
FORCEPROP 2 LAST CUSTOM_TXT_CDS <Q_NUMBER>
J 0
(4297 -1572);
DISPLAY 1.212766 (4297 -1572);
FORCEPROP 1 LAST CUSTOM_TXT_CDS <NAME_2>
J 0
(2525 -1625);
FORCEPROP 1 LAST CUSTOM_TXT_CDS <NAME_1>
J 0
(2525 -1500);
FORCEPROP 1 LAST CUSTOM_TXT_CDS <Q_PROJ>
J 0
(3318 -1573);
DISPLAY 1.212766 (3318 -1573);
FORCEPROP 1 LAST CUSTOM_TXT_CDS <Q_REV>
J 0
(5516 -1572);
DISPLAY 1.212766 (5516 -1572);
FORCEPROP 1 LAST CUSTOM_TXT_CDS <CON_PAGE_NUM> OF <CON_TOTAL_PAGES>
J 0
(5254 -1657);
DISPLAY 0.978723 (5254 -1657);
FORCEPROP 1 LAST Q_TITLE SPR CPU0 - PCIE PE2/PE3 (18 OF 30)
J 0
(-3666 -1649);
DISPLAY 1.957447 (-3666 -1649);
PAINT GREEN (-3666 -1649);
FORCEPROP 1 LAST Q_DEPT 
J 1
(1937 -1626);
DISPLAY 1.957447 (1937 -1626);
PAINT GREEN (1937 -1626);
FORCEPROP 2 LAST PAGE_BORDER TRUE
J 0
(-2190 3575);
DISPLAY 0.638298 (-2190 3575);
PAINT PINK (-2190 3575);
DISPLAY INVISIBLE (-2190 3575);
FORCEPROP 1 LAST CDS_LMAN_SYM_OUTLINE -9475,6775,100,-125
J 0
(5700 -1675);
DISPLAY 0.468085 (5700 -1675);
PAINT GREEN (5700 -1675);
DISPLAY INVISIBLE (5700 -1675);
FORCEPROP 2 LAST CDS_LIB pure_quanta
J 0
(5700 -1675);
PAINT MONO (5700 -1675);
DISPLAY INVISIBLE (5700 -1675);
FORCEPROP 2 LAST CDS_XR_PAGE_TITLE CR-30 : @S9S_MB_2U_LIB.S9S_MB_2U(SCH_1):PAGE30
J 0
(-2190 3575);
DISPLAY 0.638298 (-2190 3575);
PAINT PINK (-2190 3575);
DISPLAY INVISIBLE (-2190 3575);
FORCEPROP 1 LAST COMMENT_BODY TRUE
J 0
(5712 -1688);
DISPLAY 0.978723 (5712 -1688);
PAINT GREEN (5712 -1688);
DISPLAY INVISIBLE (5712 -1688);
WIRE 17 -1 (2875 325)(2875 375);
WIRE 17 -1 (2875 375)(2875 425);
WIRE 17 -1 (2875 425)(2875 475);
WIRE 17 -1 (2875 475)(2875 525);
WIRE 17 -1 (2875 525)(2875 575);
WIRE 17 -1 (2875 575)(2875 625);
WIRE 17 -1 (2875 625)(2875 675);
WIRE 17 -1 (2875 675)(2875 725);
WIRE 17 -1 (2875 725)(2875 775);
WIRE 17 -1 (2875 775)(2875 825);
WIRE 17 -1 (2875 825)(2875 875);
WIRE 17 -1 (2875 875)(2875 925);
WIRE 17 -1 (2875 925)(2875 975);
WIRE 17 -1 (2875 975)(2875 1025);
WIRE 17 -1 (2875 1025)(2875 1075);
WIRE 17 -1 (2875 1075)(3875 1075);
FORCEPROP 2 LAST SIG_NAME P5E_CPU0_PE3_TX_DP<15:0>
J 0
(3015 1085);
DISPLAY 0.680851 (3015 1085);
PAINT WHITE (3015 1085);
WIRE 17 -1 (2875 -525)(2875 -475);
WIRE 17 -1 (2875 -475)(2875 -425);
WIRE 17 -1 (2875 -425)(2875 -375);
WIRE 17 -1 (2875 -375)(2875 -325);
WIRE 17 -1 (2875 -325)(2875 -275);
WIRE 17 -1 (2875 -275)(2875 -225);
WIRE 17 -1 (2875 -225)(2875 -175);
WIRE 17 -1 (2875 -175)(2875 -125);
WIRE 17 -1 (2875 -125)(2875 -75);
WIRE 17 -1 (2875 -75)(2875 -25);
WIRE 17 -1 (2875 -25)(2875 25);
WIRE 17 -1 (2875 25)(2875 75);
WIRE 17 -1 (2875 75)(2875 125);
WIRE 17 -1 (2875 125)(2875 175);
WIRE 17 -1 (2875 175)(2875 225);
WIRE 17 -1 (2875 225)(3875 225);
FORCEPROP 2 LAST SIG_NAME P5E_CPU0_PE3_TX_DN<15:0>
J 0
(3015 235);
DISPLAY 0.680851 (3015 235);
PAINT WHITE (3015 235);
WIRE 17 -1 (-625 325)(-625 375);
WIRE 17 -1 (-625 375)(-625 425);
WIRE 17 -1 (-625 425)(-625 475);
WIRE 17 -1 (-625 475)(-625 525);
WIRE 17 -1 (-625 525)(-625 575);
WIRE 17 -1 (-625 575)(-625 625);
WIRE 17 -1 (-625 625)(-625 675);
WIRE 17 -1 (-625 675)(-625 725);
WIRE 17 -1 (-625 725)(-625 775);
WIRE 17 -1 (-625 775)(-625 825);
WIRE 17 -1 (-625 825)(-625 875);
WIRE 17 -1 (-625 875)(-625 925);
WIRE 17 -1 (-625 925)(-625 975);
WIRE 17 -1 (-625 975)(-625 1025);
WIRE 17 -1 (-625 1025)(-625 1075);
WIRE 17 -1 (-1775 1075)(-625 1075);
FORCEPROP 2 LAST SIG_NAME P5E_CPU0_PE3_RX_DP<15:0>
J 0
(-1660 1085);
DISPLAY 0.680851 (-1660 1085);
PAINT WHITE (-1660 1085);
WIRE 17 -1 (-625 -525)(-625 -475);
WIRE 17 -1 (-625 -475)(-625 -425);
WIRE 17 -1 (-625 -425)(-625 -375);
WIRE 17 -1 (-625 -375)(-625 -325);
WIRE 17 -1 (-625 -325)(-625 -275);
WIRE 17 -1 (-625 -275)(-625 -225);
WIRE 17 -1 (-625 -225)(-625 -175);
WIRE 17 -1 (-625 -175)(-625 -125);
WIRE 17 -1 (-625 -125)(-625 -75);
WIRE 17 -1 (-625 -75)(-625 -25);
WIRE 17 -1 (-625 -25)(-625 25);
WIRE 17 -1 (-625 25)(-625 75);
WIRE 17 -1 (-625 75)(-625 125);
WIRE 17 -1 (-625 125)(-625 175);
WIRE 17 -1 (-625 175)(-625 225);
WIRE 17 -1 (-1775 225)(-625 225);
FORCEPROP 2 LAST SIG_NAME P5E_CPU0_PE3_RX_DN<15:0>
J 0
(-1660 235);
DISPLAY 0.680851 (-1660 235);
PAINT WHITE (-1660 235);
WIRE 17 -1 (2875 3100)(2875 3150);
WIRE 17 -1 (2875 3150)(2875 3200);
WIRE 17 -1 (2875 3200)(2875 3250);
WIRE 17 -1 (2875 3250)(2875 3300);
WIRE 17 -1 (2875 3300)(2875 3350);
WIRE 17 -1 (2875 3350)(2875 3400);
WIRE 17 -1 (2875 3400)(2875 3450);
WIRE 17 -1 (2875 3450)(2875 3500);
WIRE 17 -1 (2875 3500)(2875 3550);
WIRE 17 -1 (2875 3550)(2875 3600);
WIRE 17 -1 (2875 3600)(2875 3650);
WIRE 17 -1 (2875 3650)(2875 3700);
WIRE 17 -1 (2875 3700)(2875 3750);
WIRE 17 -1 (2875 3750)(2875 3800);
WIRE 17 -1 (2875 3800)(2875 3850);
WIRE 17 -1 (2875 3850)(3875 3850);
FORCEPROP 2 LAST SIG_NAME P5E_CPU0_PE2_TX_DP<15:0>
J 0
(3015 3860);
DISPLAY 0.680851 (3015 3860);
PAINT WHITE (3015 3860);
WIRE 17 -1 (2875 2250)(2875 2300);
WIRE 17 -1 (2875 2300)(2875 2350);
WIRE 17 -1 (2875 2350)(2875 2400);
WIRE 17 -1 (2875 2400)(2875 2450);
WIRE 17 -1 (2875 2450)(2875 2500);
WIRE 17 -1 (2875 2500)(2875 2550);
WIRE 17 -1 (2875 2550)(2875 2600);
WIRE 17 -1 (2875 2600)(2875 2650);
WIRE 17 -1 (2875 2650)(2875 2700);
WIRE 17 -1 (2875 2700)(2875 2750);
WIRE 17 -1 (2875 2750)(2875 2800);
WIRE 17 -1 (2875 2800)(2875 2850);
WIRE 17 -1 (2875 2850)(2875 2900);
WIRE 17 -1 (2875 2900)(2875 2950);
WIRE 17 -1 (2875 2950)(2875 3000);
WIRE 17 -1 (2875 3000)(3875 3000);
FORCEPROP 2 LAST SIG_NAME P5E_CPU0_PE2_TX_DN<15:0>
J 0
(3015 3010);
DISPLAY 0.680851 (3015 3010);
PAINT WHITE (3015 3010);
WIRE 17 -1 (-650 3100)(-650 3150);
WIRE 17 -1 (-650 3150)(-650 3200);
WIRE 17 -1 (-650 3200)(-650 3250);
WIRE 17 -1 (-650 3250)(-650 3300);
WIRE 17 -1 (-650 3300)(-650 3350);
WIRE 17 -1 (-650 3350)(-650 3400);
WIRE 17 -1 (-650 3400)(-650 3450);
WIRE 17 -1 (-650 3450)(-650 3500);
WIRE 17 -1 (-650 3500)(-650 3550);
WIRE 17 -1 (-650 3550)(-650 3600);
WIRE 17 -1 (-650 3600)(-650 3650);
WIRE 17 -1 (-650 3650)(-650 3700);
WIRE 17 -1 (-650 3700)(-650 3750);
WIRE 17 -1 (-650 3750)(-650 3800);
WIRE 17 -1 (-650 3800)(-650 3850);
WIRE 17 -1 (-1800 3850)(-650 3850);
FORCEPROP 2 LAST SIG_NAME P5E_CPU0_PE2_RX_DP<15:0>
J 0
(-1685 3860);
DISPLAY 0.680851 (-1685 3860);
PAINT WHITE (-1685 3860);
WIRE 17 -1 (-650 2250)(-650 2300);
WIRE 17 -1 (-650 2300)(-650 2350);
WIRE 17 -1 (-650 2350)(-650 2400);
WIRE 17 -1 (-650 2400)(-650 2450);
WIRE 17 -1 (-650 2450)(-650 2500);
WIRE 17 -1 (-650 2500)(-650 2550);
WIRE 17 -1 (-650 2550)(-650 2600);
WIRE 17 -1 (-650 2600)(-650 2650);
WIRE 17 -1 (-650 2650)(-650 2700);
WIRE 17 -1 (-650 2700)(-650 2750);
WIRE 17 -1 (-650 2750)(-650 2800);
WIRE 17 -1 (-650 2800)(-650 2850);
WIRE 17 -1 (-650 2850)(-650 2900);
WIRE 17 -1 (-650 2900)(-650 2950);
WIRE 17 -1 (-650 2950)(-650 3000);
WIRE 17 -1 (-1800 3000)(-650 3000);
FORCEPROP 2 LAST SIG_NAME P5E_CPU0_PE2_RX_DN<15:0>
J 0
(-1685 3010);
DISPLAY 0.680851 (-1685 3010);
PAINT WHITE (-1685 3010);
WIRE 16 -1 (-550 2975)(-100 2975);
WIRE 16 -1 (-550 2925)(-100 2925);
WIRE 16 -1 (-550 2875)(-100 2875);
WIRE 16 -1 (-550 2825)(-100 2825);
WIRE 16 -1 (-550 2775)(-100 2775);
WIRE 16 -1 (-550 2725)(-100 2725);
WIRE 16 -1 (-550 2675)(-100 2675);
WIRE 16 -1 (-550 2625)(-100 2625);
WIRE 16 -1 (-550 2575)(-100 2575);
WIRE 16 -1 (-550 2525)(-100 2525);
WIRE 16 -1 (-550 2475)(-100 2475);
WIRE 16 -1 (-550 2425)(-100 2425);
WIRE 16 -1 (-550 2375)(-100 2375);
WIRE 16 -1 (-550 2325)(-100 2325);
WIRE 16 -1 (-550 2275)(-100 2275);
WIRE 16 -1 (-550 2225)(-100 2225);
WIRE 16 -1 (-550 3825)(-100 3825);
WIRE 16 -1 (-550 3775)(-100 3775);
WIRE 16 -1 (-550 3725)(-100 3725);
WIRE 16 -1 (-550 3675)(-100 3675);
WIRE 16 -1 (-550 3625)(-100 3625);
WIRE 16 -1 (-550 3575)(-100 3575);
WIRE 16 -1 (-550 3525)(-100 3525);
WIRE 16 -1 (-550 3475)(-100 3475);
WIRE 16 -1 (-550 3425)(-100 3425);
WIRE 16 -1 (-550 3375)(-100 3375);
WIRE 16 -1 (-550 3325)(-100 3325);
WIRE 16 -1 (-550 3275)(-100 3275);
WIRE 16 -1 (-550 3225)(-100 3225);
WIRE 16 -1 (-550 3175)(-100 3175);
WIRE 16 -1 (-550 3125)(-100 3125);
WIRE 16 -1 (-550 3075)(-100 3075);
WIRE 16 -1 (2300 2975)(2775 2975);
WIRE 16 -1 (2300 2925)(2775 2925);
WIRE 16 -1 (2300 2875)(2775 2875);
WIRE 16 -1 (2300 2825)(2775 2825);
WIRE 16 -1 (2300 2775)(2775 2775);
WIRE 16 -1 (2300 2725)(2775 2725);
WIRE 16 -1 (2300 2675)(2775 2675);
WIRE 16 -1 (2300 2625)(2775 2625);
WIRE 16 -1 (2300 2575)(2775 2575);
WIRE 16 -1 (2300 2525)(2775 2525);
WIRE 16 -1 (2300 2475)(2775 2475);
WIRE 16 -1 (2300 2425)(2775 2425);
WIRE 16 -1 (2300 2375)(2775 2375);
WIRE 16 -1 (2300 2325)(2775 2325);
WIRE 16 -1 (2300 2275)(2775 2275);
WIRE 16 -1 (2300 2225)(2775 2225);
WIRE 16 -1 (2300 3825)(2775 3825);
WIRE 16 -1 (2300 3775)(2775 3775);
WIRE 16 -1 (2300 3725)(2775 3725);
WIRE 16 -1 (2300 3675)(2775 3675);
WIRE 16 -1 (2300 3625)(2775 3625);
WIRE 16 -1 (2300 3575)(2775 3575);
WIRE 16 -1 (2300 3525)(2775 3525);
WIRE 16 -1 (2300 3475)(2775 3475);
WIRE 16 -1 (2300 3425)(2775 3425);
WIRE 16 -1 (2300 3375)(2775 3375);
WIRE 16 -1 (2300 3325)(2775 3325);
WIRE 16 -1 (2300 3275)(2775 3275);
WIRE 16 -1 (2300 3225)(2775 3225);
WIRE 16 -1 (2300 3175)(2775 3175);
WIRE 16 -1 (2300 3125)(2775 3125);
WIRE 16 -1 (2300 3075)(2775 3075);
WIRE 16 -1 (-525 200)(-100 200);
WIRE 16 -1 (-525 150)(-100 150);
WIRE 16 -1 (-525 100)(-100 100);
WIRE 16 -1 (-525 50)(-100 50);
WIRE 16 -1 (-525 0)(-100 0);
WIRE 16 -1 (-525 -50)(-100 -50);
WIRE 16 -1 (-525 -100)(-100 -100);
WIRE 16 -1 (-525 -150)(-100 -150);
WIRE 16 -1 (-525 -200)(-100 -200);
WIRE 16 -1 (-525 -250)(-100 -250);
WIRE 16 -1 (-525 -300)(-100 -300);
WIRE 16 -1 (-525 -350)(-100 -350);
WIRE 16 -1 (-525 -400)(-100 -400);
WIRE 16 -1 (-525 -450)(-100 -450);
WIRE 16 -1 (-525 -500)(-100 -500);
WIRE 16 -1 (-525 -550)(-100 -550);
WIRE 16 -1 (-525 1050)(-100 1050);
WIRE 16 -1 (-525 1000)(-100 1000);
WIRE 16 -1 (-525 950)(-100 950);
WIRE 16 -1 (-525 900)(-100 900);
WIRE 16 -1 (-525 850)(-100 850);
WIRE 16 -1 (-525 800)(-100 800);
WIRE 16 -1 (-525 750)(-100 750);
WIRE 16 -1 (-525 700)(-100 700);
WIRE 16 -1 (-525 650)(-100 650);
WIRE 16 -1 (-525 600)(-100 600);
WIRE 16 -1 (-525 550)(-100 550);
WIRE 16 -1 (-525 500)(-100 500);
WIRE 16 -1 (-525 450)(-100 450);
WIRE 16 -1 (-525 400)(-100 400);
WIRE 16 -1 (-525 350)(-100 350);
WIRE 16 -1 (-525 300)(-100 300);
WIRE 16 -1 (2300 200)(2775 200);
WIRE 16 -1 (2300 150)(2775 150);
WIRE 16 -1 (2300 100)(2775 100);
WIRE 16 -1 (2300 50)(2775 50);
WIRE 16 -1 (2300 0)(2775 0);
WIRE 16 -1 (2300 -50)(2775 -50);
WIRE 16 -1 (2300 -100)(2775 -100);
WIRE 16 -1 (2300 -150)(2775 -150);
WIRE 16 -1 (2300 -200)(2775 -200);
WIRE 16 -1 (2300 -250)(2775 -250);
WIRE 16 -1 (2300 -300)(2775 -300);
WIRE 16 -1 (2300 -350)(2775 -350);
WIRE 16 -1 (2300 -400)(2775 -400);
WIRE 16 -1 (2300 -450)(2775 -450);
WIRE 16 -1 (2300 -500)(2775 -500);
WIRE 16 -1 (2300 -550)(2775 -550);
WIRE 16 -1 (2300 1050)(2775 1050);
WIRE 16 -1 (2300 1000)(2775 1000);
WIRE 16 -1 (2300 950)(2775 950);
WIRE 16 -1 (2300 900)(2775 900);
WIRE 16 -1 (2300 850)(2775 850);
WIRE 16 -1 (2300 800)(2775 800);
WIRE 16 -1 (2300 750)(2775 750);
WIRE 16 -1 (2300 700)(2775 700);
WIRE 16 -1 (2300 650)(2775 650);
WIRE 16 -1 (2300 600)(2775 600);
WIRE 16 -1 (2300 550)(2775 550);
WIRE 16 -1 (2300 500)(2775 500);
WIRE 16 -1 (2300 450)(2775 450);
WIRE 16 -1 (2300 400)(2775 400);
WIRE 16 -1 (2300 350)(2775 350);
WIRE 16 -1 (2300 300)(2775 300);
WIRE 16 2175 (2975 2850)(4300 2850);
WIRE 16 2175 (4300 4050)(4300 2850);
WIRE 16 2175 (2975 4050)(2975 2850);
WIRE 16 2175 (2975 4050)(4300 4050);
FORCENOTE
20210818 MODIFY FOR GT
(-250 4625) 0;
DISPLAY LEFT (-250 4625);
DISPLAY 2.510638 (-250 4625);
PAINT PINK (-250 4625);
FORCENOTE
20211126 SWAP DP/DN
(3000 2675) 0;
DISPLAY LEFT (3000 2675);
DISPLAY 2.510638 (3000 2675);
PAINT PINK (3000 2675);
QUIT
